FILE_TYPE = MACRO_DRAWING;
SET COLOR_WIRE YELLOW;
SET COLOR_PROP ORANGE;
SET COLOR_DOT WHITE;
SET COLOR_ARC YELLOW;
SET COLOR_BODY GREEN;
SET COLOR_NOTE PURPLE;
SET PROP_DISPLAY VALUE;
SET PAGE_NUMBER P94;
FORCEADD OFFPAGE..5
(-8250 1875);
FORCEPROP 2 LAST $XR0 19 
J 0
(-8474 1875);
DISPLAY 0.638298 (-8474 1875);
PAINT MONO (-8474 1875);
FORCEPROP 2 LAST CDS_LIB mstr_standard
J 0
(-8250 1875);
DISPLAY 0.808511 (-8250 1875);
DISPLAY INVISIBLE (-8250 1875);
FORCEPROP 1 LAST OFFPAGE TRUE
J 0
(-7925 1750);
DISPLAY 0.872340 (-7925 1750);
PAINT GREEN (-7925 1750);
DISPLAY INVISIBLE (-7925 1750);
FORCEPROP 1 LAST COMMENT_BODY TRUE
J 0
(-8150 1800);
DISPLAY 0.872340 (-8150 1800);
PAINT GREEN (-8150 1800);
DISPLAY INVISIBLE (-8150 1800);
FORCEPROP 2 LAST PATH I1
J 0
(-8200 1950);
DISPLAY 1.021277 (-8200 1950);
DISPLAY INVISIBLE (-8200 1950);
FORCEADD OFFPAGE..6
(-8250 3525);
FORCEPROP 2 LAST $XR0 19 
J 0
(-8529 3525);
DISPLAY 0.638298 (-8529 3525);
PAINT MONO (-8529 3525);
FORCEPROP 2 LAST CDS_LIB mstr_standard
J 0
(-8250 3525);
DISPLAY 0.723404 (-8250 3525);
PAINT MONO (-8250 3525);
DISPLAY INVISIBLE (-8250 3525);
FORCEPROP 1 LAST OFFPAGE TRUE
J 0
(-7925 3400);
DISPLAY 0.872340 (-7925 3400);
PAINT GREEN (-7925 3400);
DISPLAY INVISIBLE (-7925 3400);
FORCEPROP 1 LAST COMMENT_BODY TRUE
J 0
(-8150 3450);
DISPLAY 0.872340 (-8150 3450);
PAINT GREEN (-8150 3450);
DISPLAY INVISIBLE (-8150 3450);
FORCEPROP 2 LAST PATH I10
J 0
(-8200 3600);
DISPLAY 1.021277 (-8200 3600);
DISPLAY INVISIBLE (-8200 3600);
FORCEADD TAP..1
(-5950 4075);
FORCEPROP 3 LASTPIN (-6000 4075) SIG_NAME M_J_CPU0_SA_DQ<6>
J 0
(-5990 4085);
DISPLAY 0.659574 (-5990 4085);
PAINT MONO (-5990 4085);
DISPLAY INVISIBLE (-5990 4085);
FORCEPROP 1 LASTPIN (-6000 4075) BN 6
J 0
(-6012 4083);
DISPLAY 0.489362 (-6012 4083);
PAINT GREEN (-6012 4083);
FORCEPROP 2 LAST CDS_LIB mstr_standard
J 0
(-5950 4075);
DISPLAY 0.723404 (-5950 4075);
PAINT MONO (-5950 4075);
DISPLAY INVISIBLE (-5950 4075);
FORCEPROP 1 LAST BODY_TYPE PLUMBING
J 0
(-5950 4125);
DISPLAY 0.872340 (-5950 4125);
PAINT GREEN (-5950 4125);
DISPLAY INVISIBLE (-5950 4125);
FORCEPROP 1 LAST HDL_TAP TRUE
J 0
(-5625 3950);
DISPLAY 0.872340 (-5625 3950);
DISPLAY INVISIBLE (-5625 3950);
FORCEPROP 1 LAST PATH I100
J 0
(-5952 4075);
DISPLAY 0.872340 (-5952 4075);
PAINT GREEN (-5952 4075);
DISPLAY INVISIBLE (-5952 4075);
FORCEADD TAP..1
(-5950 4125);
FORCEPROP 3 LASTPIN (-6000 4125) SIG_NAME M_J_CPU0_SA_DQ<7>
J 0
(-5990 4135);
DISPLAY 0.659574 (-5990 4135);
PAINT MONO (-5990 4135);
DISPLAY INVISIBLE (-5990 4135);
FORCEPROP 1 LASTPIN (-6000 4125) BN 7
J 0
(-6012 4133);
DISPLAY 0.489362 (-6012 4133);
PAINT GREEN (-6012 4133);
FORCEPROP 2 LAST CDS_LIB mstr_standard
J 0
(-5950 4125);
DISPLAY 0.723404 (-5950 4125);
PAINT MONO (-5950 4125);
DISPLAY INVISIBLE (-5950 4125);
FORCEPROP 1 LAST BODY_TYPE PLUMBING
J 0
(-5950 4175);
DISPLAY 0.872340 (-5950 4175);
PAINT GREEN (-5950 4175);
DISPLAY INVISIBLE (-5950 4175);
FORCEPROP 1 LAST HDL_TAP TRUE
J 0
(-5625 4000);
DISPLAY 0.872340 (-5625 4000);
DISPLAY INVISIBLE (-5625 4000);
FORCEPROP 1 LAST PATH I101
J 0
(-5952 4125);
DISPLAY 0.872340 (-5952 4125);
PAINT GREEN (-5952 4125);
DISPLAY INVISIBLE (-5952 4125);
FORCEADD TAP..1
(-5950 4275);
FORCEPROP 3 LASTPIN (-6000 4275) SIG_NAME M_J_CPU0_SA_DQ<10>
J 0
(-5990 4285);
DISPLAY 0.659574 (-5990 4285);
PAINT MONO (-5990 4285);
DISPLAY INVISIBLE (-5990 4285);
FORCEPROP 1 LASTPIN (-6000 4275) BN 10
J 0
(-6012 4283);
DISPLAY 0.489362 (-6012 4283);
PAINT GREEN (-6012 4283);
FORCEPROP 2 LAST CDS_LIB mstr_standard
J 0
(-5950 4275);
DISPLAY 0.723404 (-5950 4275);
PAINT MONO (-5950 4275);
DISPLAY INVISIBLE (-5950 4275);
FORCEPROP 1 LAST BODY_TYPE PLUMBING
J 0
(-5950 4325);
DISPLAY 0.872340 (-5950 4325);
PAINT GREEN (-5950 4325);
DISPLAY INVISIBLE (-5950 4325);
FORCEPROP 1 LAST HDL_TAP TRUE
J 0
(-5625 4150);
DISPLAY 0.872340 (-5625 4150);
DISPLAY INVISIBLE (-5625 4150);
FORCEPROP 1 LAST PATH I102
J 0
(-5952 4275);
DISPLAY 0.872340 (-5952 4275);
PAINT GREEN (-5952 4275);
DISPLAY INVISIBLE (-5952 4275);
FORCEADD TAP..1
(-5950 4225);
FORCEPROP 3 LASTPIN (-6000 4225) SIG_NAME M_J_CPU0_SA_DQ<9>
J 0
(-5990 4235);
DISPLAY 0.659574 (-5990 4235);
PAINT MONO (-5990 4235);
DISPLAY INVISIBLE (-5990 4235);
FORCEPROP 1 LASTPIN (-6000 4225) BN 9
J 0
(-6012 4233);
DISPLAY 0.489362 (-6012 4233);
PAINT GREEN (-6012 4233);
FORCEPROP 2 LAST CDS_LIB mstr_standard
J 0
(-5950 4225);
DISPLAY 0.723404 (-5950 4225);
PAINT MONO (-5950 4225);
DISPLAY INVISIBLE (-5950 4225);
FORCEPROP 1 LAST BODY_TYPE PLUMBING
J 0
(-5950 4275);
DISPLAY 0.872340 (-5950 4275);
PAINT GREEN (-5950 4275);
DISPLAY INVISIBLE (-5950 4275);
FORCEPROP 1 LAST HDL_TAP TRUE
J 0
(-5625 4100);
DISPLAY 0.872340 (-5625 4100);
DISPLAY INVISIBLE (-5625 4100);
FORCEPROP 1 LAST PATH I103
J 0
(-5952 4225);
DISPLAY 0.872340 (-5952 4225);
PAINT GREEN (-5952 4225);
DISPLAY INVISIBLE (-5952 4225);
FORCEADD TAP..1
(-5950 4175);
FORCEPROP 3 LASTPIN (-6000 4175) SIG_NAME M_J_CPU0_SA_DQ<8>
J 0
(-5990 4185);
DISPLAY 0.659574 (-5990 4185);
PAINT MONO (-5990 4185);
DISPLAY INVISIBLE (-5990 4185);
FORCEPROP 1 LASTPIN (-6000 4175) BN 8
J 0
(-6012 4183);
DISPLAY 0.489362 (-6012 4183);
PAINT GREEN (-6012 4183);
FORCEPROP 2 LAST CDS_LIB mstr_standard
J 0
(-5950 4175);
DISPLAY 0.723404 (-5950 4175);
PAINT MONO (-5950 4175);
DISPLAY INVISIBLE (-5950 4175);
FORCEPROP 1 LAST BODY_TYPE PLUMBING
J 0
(-5950 4225);
DISPLAY 0.872340 (-5950 4225);
PAINT GREEN (-5950 4225);
DISPLAY INVISIBLE (-5950 4225);
FORCEPROP 1 LAST HDL_TAP TRUE
J 0
(-5625 4050);
DISPLAY 0.872340 (-5625 4050);
DISPLAY INVISIBLE (-5625 4050);
FORCEPROP 1 LAST PATH I104
J 0
(-5952 4175);
DISPLAY 0.872340 (-5952 4175);
PAINT GREEN (-5952 4175);
DISPLAY INVISIBLE (-5952 4175);
FORCEADD TAP..1
(-5950 4325);
FORCEPROP 3 LASTPIN (-6000 4325) SIG_NAME M_J_CPU0_SA_DQ<11>
J 0
(-5990 4335);
DISPLAY 0.659574 (-5990 4335);
PAINT MONO (-5990 4335);
DISPLAY INVISIBLE (-5990 4335);
FORCEPROP 1 LASTPIN (-6000 4325) BN 11
J 0
(-6012 4333);
DISPLAY 0.489362 (-6012 4333);
PAINT GREEN (-6012 4333);
FORCEPROP 2 LAST CDS_LIB mstr_standard
J 0
(-5950 4325);
DISPLAY 0.723404 (-5950 4325);
PAINT MONO (-5950 4325);
DISPLAY INVISIBLE (-5950 4325);
FORCEPROP 1 LAST BODY_TYPE PLUMBING
J 0
(-5950 4375);
DISPLAY 0.872340 (-5950 4375);
PAINT GREEN (-5950 4375);
DISPLAY INVISIBLE (-5950 4375);
FORCEPROP 1 LAST HDL_TAP TRUE
J 0
(-5625 4200);
DISPLAY 0.872340 (-5625 4200);
DISPLAY INVISIBLE (-5625 4200);
FORCEPROP 1 LAST PATH I105
J 0
(-5952 4325);
DISPLAY 0.872340 (-5952 4325);
PAINT GREEN (-5952 4325);
DISPLAY INVISIBLE (-5952 4325);
FORCEADD TAP..1
(-5950 4375);
FORCEPROP 3 LASTPIN (-6000 4375) SIG_NAME M_J_CPU0_SA_DQ<12>
J 0
(-5990 4385);
DISPLAY 0.659574 (-5990 4385);
PAINT MONO (-5990 4385);
DISPLAY INVISIBLE (-5990 4385);
FORCEPROP 1 LASTPIN (-6000 4375) BN 12
J 0
(-6012 4383);
DISPLAY 0.489362 (-6012 4383);
PAINT GREEN (-6012 4383);
FORCEPROP 2 LAST CDS_LIB mstr_standard
J 0
(-5950 4375);
DISPLAY 0.723404 (-5950 4375);
PAINT MONO (-5950 4375);
DISPLAY INVISIBLE (-5950 4375);
FORCEPROP 1 LAST BODY_TYPE PLUMBING
J 0
(-5950 4425);
DISPLAY 0.872340 (-5950 4425);
PAINT GREEN (-5950 4425);
DISPLAY INVISIBLE (-5950 4425);
FORCEPROP 1 LAST HDL_TAP TRUE
J 0
(-5625 4250);
DISPLAY 0.872340 (-5625 4250);
DISPLAY INVISIBLE (-5625 4250);
FORCEPROP 1 LAST PATH I106
J 0
(-5952 4375);
DISPLAY 0.872340 (-5952 4375);
PAINT GREEN (-5952 4375);
DISPLAY INVISIBLE (-5952 4375);
FORCEADD TAP..1
(-5950 4425);
FORCEPROP 3 LASTPIN (-6000 4425) SIG_NAME M_J_CPU0_SA_DQ<13>
J 0
(-5990 4435);
DISPLAY 0.659574 (-5990 4435);
PAINT MONO (-5990 4435);
DISPLAY INVISIBLE (-5990 4435);
FORCEPROP 1 LASTPIN (-6000 4425) BN 13
J 0
(-6012 4433);
DISPLAY 0.489362 (-6012 4433);
PAINT GREEN (-6012 4433);
FORCEPROP 2 LAST CDS_LIB mstr_standard
J 0
(-5950 4425);
DISPLAY 0.723404 (-5950 4425);
PAINT MONO (-5950 4425);
DISPLAY INVISIBLE (-5950 4425);
FORCEPROP 1 LAST BODY_TYPE PLUMBING
J 0
(-5950 4475);
DISPLAY 0.872340 (-5950 4475);
PAINT GREEN (-5950 4475);
DISPLAY INVISIBLE (-5950 4475);
FORCEPROP 1 LAST HDL_TAP TRUE
J 0
(-5625 4300);
DISPLAY 0.872340 (-5625 4300);
DISPLAY INVISIBLE (-5625 4300);
FORCEPROP 1 LAST PATH I107
J 0
(-5952 4425);
DISPLAY 0.872340 (-5952 4425);
PAINT GREEN (-5952 4425);
DISPLAY INVISIBLE (-5952 4425);
FORCEADD TAP..1
(-5950 4475);
FORCEPROP 3 LASTPIN (-6000 4475) SIG_NAME M_J_CPU0_SA_DQ<14>
J 0
(-5990 4485);
DISPLAY 0.659574 (-5990 4485);
PAINT MONO (-5990 4485);
DISPLAY INVISIBLE (-5990 4485);
FORCEPROP 1 LASTPIN (-6000 4475) BN 14
J 0
(-6012 4483);
DISPLAY 0.489362 (-6012 4483);
PAINT GREEN (-6012 4483);
FORCEPROP 2 LAST CDS_LIB mstr_standard
J 0
(-5950 4475);
DISPLAY 0.723404 (-5950 4475);
PAINT MONO (-5950 4475);
DISPLAY INVISIBLE (-5950 4475);
FORCEPROP 1 LAST BODY_TYPE PLUMBING
J 0
(-5950 4525);
DISPLAY 0.872340 (-5950 4525);
PAINT GREEN (-5950 4525);
DISPLAY INVISIBLE (-5950 4525);
FORCEPROP 1 LAST HDL_TAP TRUE
J 0
(-5625 4350);
DISPLAY 0.872340 (-5625 4350);
DISPLAY INVISIBLE (-5625 4350);
FORCEPROP 1 LAST PATH I108
J 0
(-5952 4475);
DISPLAY 0.872340 (-5952 4475);
PAINT GREEN (-5952 4475);
DISPLAY INVISIBLE (-5952 4475);
FORCEADD TAP..1
(-5950 4525);
FORCEPROP 3 LASTPIN (-6000 4525) SIG_NAME M_J_CPU0_SA_DQ<15>
J 0
(-5990 4535);
DISPLAY 0.659574 (-5990 4535);
PAINT MONO (-5990 4535);
DISPLAY INVISIBLE (-5990 4535);
FORCEPROP 1 LASTPIN (-6000 4525) BN 15
J 0
(-6012 4533);
DISPLAY 0.489362 (-6012 4533);
PAINT GREEN (-6012 4533);
FORCEPROP 2 LAST CDS_LIB mstr_standard
J 0
(-5950 4525);
DISPLAY 0.723404 (-5950 4525);
PAINT MONO (-5950 4525);
DISPLAY INVISIBLE (-5950 4525);
FORCEPROP 1 LAST BODY_TYPE PLUMBING
J 0
(-5950 4575);
DISPLAY 0.872340 (-5950 4575);
PAINT GREEN (-5950 4575);
DISPLAY INVISIBLE (-5950 4575);
FORCEPROP 1 LAST HDL_TAP TRUE
J 0
(-5625 4400);
DISPLAY 0.872340 (-5625 4400);
DISPLAY INVISIBLE (-5625 4400);
FORCEPROP 1 LAST PATH I109
J 0
(-5952 4525);
DISPLAY 0.872340 (-5952 4525);
PAINT GREEN (-5952 4525);
DISPLAY INVISIBLE (-5952 4525);
FORCEADD OFFPAGE..6
(-8250 3975);
FORCEPROP 2 LAST $XR0 19 
J 0
(-8529 3975);
DISPLAY 0.638298 (-8529 3975);
PAINT MONO (-8529 3975);
FORCEPROP 2 LAST CDS_LIB mstr_standard
J 0
(-8250 3975);
DISPLAY 0.723404 (-8250 3975);
PAINT MONO (-8250 3975);
DISPLAY INVISIBLE (-8250 3975);
FORCEPROP 1 LAST OFFPAGE TRUE
J 0
(-7925 3850);
DISPLAY 0.872340 (-7925 3850);
PAINT GREEN (-7925 3850);
DISPLAY INVISIBLE (-7925 3850);
FORCEPROP 1 LAST COMMENT_BODY TRUE
J 0
(-8150 3900);
DISPLAY 0.872340 (-8150 3900);
PAINT GREEN (-8150 3900);
DISPLAY INVISIBLE (-8150 3900);
FORCEPROP 2 LAST PATH I11
J 0
(-8200 4050);
DISPLAY 1.021277 (-8200 4050);
DISPLAY INVISIBLE (-8200 4050);
FORCEADD TAP..1
(-5950 4625);
FORCEPROP 3 LASTPIN (-6000 4625) SIG_NAME M_J_CPU0_SA_DQ<17>
J 0
(-5990 4635);
DISPLAY 0.659574 (-5990 4635);
PAINT MONO (-5990 4635);
DISPLAY INVISIBLE (-5990 4635);
FORCEPROP 1 LASTPIN (-6000 4625) BN 17
J 0
(-6012 4633);
DISPLAY 0.489362 (-6012 4633);
PAINT GREEN (-6012 4633);
FORCEPROP 2 LAST CDS_LIB mstr_standard
J 0
(-5950 4625);
DISPLAY 0.723404 (-5950 4625);
PAINT MONO (-5950 4625);
DISPLAY INVISIBLE (-5950 4625);
FORCEPROP 1 LAST BODY_TYPE PLUMBING
J 0
(-5950 4675);
DISPLAY 0.872340 (-5950 4675);
PAINT GREEN (-5950 4675);
DISPLAY INVISIBLE (-5950 4675);
FORCEPROP 1 LAST HDL_TAP TRUE
J 0
(-5625 4500);
DISPLAY 0.872340 (-5625 4500);
DISPLAY INVISIBLE (-5625 4500);
FORCEPROP 1 LAST PATH I110
J 0
(-5952 4625);
DISPLAY 0.872340 (-5952 4625);
PAINT GREEN (-5952 4625);
DISPLAY INVISIBLE (-5952 4625);
FORCEADD TAP..1
(-5950 4575);
FORCEPROP 3 LASTPIN (-6000 4575) SIG_NAME M_J_CPU0_SA_DQ<16>
J 0
(-5990 4585);
DISPLAY 0.659574 (-5990 4585);
PAINT MONO (-5990 4585);
DISPLAY INVISIBLE (-5990 4585);
FORCEPROP 1 LASTPIN (-6000 4575) BN 16
J 0
(-6012 4583);
DISPLAY 0.489362 (-6012 4583);
PAINT GREEN (-6012 4583);
FORCEPROP 2 LAST CDS_LIB mstr_standard
J 0
(-5950 4575);
DISPLAY 0.723404 (-5950 4575);
PAINT MONO (-5950 4575);
DISPLAY INVISIBLE (-5950 4575);
FORCEPROP 1 LAST BODY_TYPE PLUMBING
J 0
(-5950 4625);
DISPLAY 0.872340 (-5950 4625);
PAINT GREEN (-5950 4625);
DISPLAY INVISIBLE (-5950 4625);
FORCEPROP 1 LAST HDL_TAP TRUE
J 0
(-5625 4450);
DISPLAY 0.872340 (-5625 4450);
DISPLAY INVISIBLE (-5625 4450);
FORCEPROP 1 LAST PATH I111
J 0
(-5952 4575);
DISPLAY 0.872340 (-5952 4575);
PAINT GREEN (-5952 4575);
DISPLAY INVISIBLE (-5952 4575);
FORCEADD TAP..1
(-5950 4775);
FORCEPROP 3 LASTPIN (-6000 4775) SIG_NAME M_J_CPU0_SA_DQ<20>
J 0
(-5990 4785);
DISPLAY 0.659574 (-5990 4785);
PAINT MONO (-5990 4785);
DISPLAY INVISIBLE (-5990 4785);
FORCEPROP 1 LASTPIN (-6000 4775) BN 20
J 0
(-6012 4783);
DISPLAY 0.489362 (-6012 4783);
PAINT GREEN (-6012 4783);
FORCEPROP 2 LAST CDS_LIB mstr_standard
J 0
(-5950 4775);
DISPLAY 0.723404 (-5950 4775);
PAINT MONO (-5950 4775);
DISPLAY INVISIBLE (-5950 4775);
FORCEPROP 1 LAST BODY_TYPE PLUMBING
J 0
(-5950 4825);
DISPLAY 0.872340 (-5950 4825);
PAINT GREEN (-5950 4825);
DISPLAY INVISIBLE (-5950 4825);
FORCEPROP 1 LAST HDL_TAP TRUE
J 0
(-5625 4650);
DISPLAY 0.872340 (-5625 4650);
DISPLAY INVISIBLE (-5625 4650);
FORCEPROP 1 LAST PATH I112
J 0
(-5952 4775);
DISPLAY 0.872340 (-5952 4775);
PAINT GREEN (-5952 4775);
DISPLAY INVISIBLE (-5952 4775);
FORCEADD TAP..1
(-5950 4725);
FORCEPROP 3 LASTPIN (-6000 4725) SIG_NAME M_J_CPU0_SA_DQ<19>
J 0
(-5990 4735);
DISPLAY 0.659574 (-5990 4735);
PAINT MONO (-5990 4735);
DISPLAY INVISIBLE (-5990 4735);
FORCEPROP 1 LASTPIN (-6000 4725) BN 19
J 0
(-6012 4733);
DISPLAY 0.489362 (-6012 4733);
PAINT GREEN (-6012 4733);
FORCEPROP 2 LAST CDS_LIB mstr_standard
J 0
(-5950 4725);
DISPLAY 0.723404 (-5950 4725);
PAINT MONO (-5950 4725);
DISPLAY INVISIBLE (-5950 4725);
FORCEPROP 1 LAST BODY_TYPE PLUMBING
J 0
(-5950 4775);
DISPLAY 0.872340 (-5950 4775);
PAINT GREEN (-5950 4775);
DISPLAY INVISIBLE (-5950 4775);
FORCEPROP 1 LAST HDL_TAP TRUE
J 0
(-5625 4600);
DISPLAY 0.872340 (-5625 4600);
DISPLAY INVISIBLE (-5625 4600);
FORCEPROP 1 LAST PATH I113
J 0
(-5952 4725);
DISPLAY 0.872340 (-5952 4725);
PAINT GREEN (-5952 4725);
DISPLAY INVISIBLE (-5952 4725);
FORCEADD TAP..1
(-5950 4675);
FORCEPROP 3 LASTPIN (-6000 4675) SIG_NAME M_J_CPU0_SA_DQ<18>
J 0
(-5990 4685);
DISPLAY 0.659574 (-5990 4685);
PAINT MONO (-5990 4685);
DISPLAY INVISIBLE (-5990 4685);
FORCEPROP 1 LASTPIN (-6000 4675) BN 18
J 0
(-6012 4683);
DISPLAY 0.489362 (-6012 4683);
PAINT GREEN (-6012 4683);
FORCEPROP 2 LAST CDS_LIB mstr_standard
J 0
(-5950 4675);
DISPLAY 0.723404 (-5950 4675);
PAINT MONO (-5950 4675);
DISPLAY INVISIBLE (-5950 4675);
FORCEPROP 1 LAST BODY_TYPE PLUMBING
J 0
(-5950 4725);
DISPLAY 0.872340 (-5950 4725);
PAINT GREEN (-5950 4725);
DISPLAY INVISIBLE (-5950 4725);
FORCEPROP 1 LAST HDL_TAP TRUE
J 0
(-5625 4550);
DISPLAY 0.872340 (-5625 4550);
DISPLAY INVISIBLE (-5625 4550);
FORCEPROP 1 LAST PATH I114
J 0
(-5952 4675);
DISPLAY 0.872340 (-5952 4675);
PAINT GREEN (-5952 4675);
DISPLAY INVISIBLE (-5952 4675);
FORCEADD TAP..1
(-5950 4875);
FORCEPROP 3 LASTPIN (-6000 4875) SIG_NAME M_J_CPU0_SA_DQ<22>
J 0
(-5990 4885);
DISPLAY 0.659574 (-5990 4885);
PAINT MONO (-5990 4885);
DISPLAY INVISIBLE (-5990 4885);
FORCEPROP 1 LASTPIN (-6000 4875) BN 22
J 0
(-6012 4883);
DISPLAY 0.489362 (-6012 4883);
PAINT GREEN (-6012 4883);
FORCEPROP 2 LAST CDS_LIB mstr_standard
J 0
(-5950 4875);
DISPLAY 0.723404 (-5950 4875);
PAINT MONO (-5950 4875);
DISPLAY INVISIBLE (-5950 4875);
FORCEPROP 1 LAST BODY_TYPE PLUMBING
J 0
(-5950 4925);
DISPLAY 0.872340 (-5950 4925);
PAINT GREEN (-5950 4925);
DISPLAY INVISIBLE (-5950 4925);
FORCEPROP 1 LAST HDL_TAP TRUE
J 0
(-5625 4750);
DISPLAY 0.872340 (-5625 4750);
DISPLAY INVISIBLE (-5625 4750);
FORCEPROP 1 LAST PATH I115
J 0
(-5952 4875);
DISPLAY 0.872340 (-5952 4875);
PAINT GREEN (-5952 4875);
DISPLAY INVISIBLE (-5952 4875);
FORCEADD TAP..1
(-5950 4825);
FORCEPROP 3 LASTPIN (-6000 4825) SIG_NAME M_J_CPU0_SA_DQ<21>
J 0
(-5990 4835);
DISPLAY 0.659574 (-5990 4835);
PAINT MONO (-5990 4835);
DISPLAY INVISIBLE (-5990 4835);
FORCEPROP 1 LASTPIN (-6000 4825) BN 21
J 0
(-6012 4833);
DISPLAY 0.489362 (-6012 4833);
PAINT GREEN (-6012 4833);
FORCEPROP 2 LAST CDS_LIB mstr_standard
J 0
(-5950 4825);
DISPLAY 0.723404 (-5950 4825);
PAINT MONO (-5950 4825);
DISPLAY INVISIBLE (-5950 4825);
FORCEPROP 1 LAST BODY_TYPE PLUMBING
J 0
(-5950 4875);
DISPLAY 0.872340 (-5950 4875);
PAINT GREEN (-5950 4875);
DISPLAY INVISIBLE (-5950 4875);
FORCEPROP 1 LAST HDL_TAP TRUE
J 0
(-5625 4700);
DISPLAY 0.872340 (-5625 4700);
DISPLAY INVISIBLE (-5625 4700);
FORCEPROP 1 LAST PATH I116
J 0
(-5952 4825);
DISPLAY 0.872340 (-5952 4825);
PAINT GREEN (-5952 4825);
DISPLAY INVISIBLE (-5952 4825);
FORCEADD TAP..1
(-5950 5025);
FORCEPROP 3 LASTPIN (-6000 5025) SIG_NAME M_J_CPU0_SA_DQ<25>
J 0
(-5990 5035);
DISPLAY 0.659574 (-5990 5035);
PAINT MONO (-5990 5035);
DISPLAY INVISIBLE (-5990 5035);
FORCEPROP 1 LASTPIN (-6000 5025) BN 25
J 0
(-6012 5033);
DISPLAY 0.489362 (-6012 5033);
PAINT GREEN (-6012 5033);
FORCEPROP 2 LAST CDS_LIB mstr_standard
J 0
(-5950 5025);
DISPLAY 0.723404 (-5950 5025);
PAINT MONO (-5950 5025);
DISPLAY INVISIBLE (-5950 5025);
FORCEPROP 1 LAST BODY_TYPE PLUMBING
J 0
(-5950 5075);
DISPLAY 0.872340 (-5950 5075);
PAINT GREEN (-5950 5075);
DISPLAY INVISIBLE (-5950 5075);
FORCEPROP 1 LAST HDL_TAP TRUE
J 0
(-5625 4900);
DISPLAY 0.872340 (-5625 4900);
DISPLAY INVISIBLE (-5625 4900);
FORCEPROP 1 LAST PATH I117
J 0
(-5952 5025);
DISPLAY 0.872340 (-5952 5025);
PAINT GREEN (-5952 5025);
DISPLAY INVISIBLE (-5952 5025);
FORCEADD TAP..1
(-5950 4975);
FORCEPROP 3 LASTPIN (-6000 4975) SIG_NAME M_J_CPU0_SA_DQ<24>
J 0
(-5990 4985);
DISPLAY 0.659574 (-5990 4985);
PAINT MONO (-5990 4985);
DISPLAY INVISIBLE (-5990 4985);
FORCEPROP 1 LASTPIN (-6000 4975) BN 24
J 0
(-6012 4983);
DISPLAY 0.489362 (-6012 4983);
PAINT GREEN (-6012 4983);
FORCEPROP 2 LAST CDS_LIB mstr_standard
J 0
(-5950 4975);
DISPLAY 0.723404 (-5950 4975);
PAINT MONO (-5950 4975);
DISPLAY INVISIBLE (-5950 4975);
FORCEPROP 1 LAST BODY_TYPE PLUMBING
J 0
(-5950 5025);
DISPLAY 0.872340 (-5950 5025);
PAINT GREEN (-5950 5025);
DISPLAY INVISIBLE (-5950 5025);
FORCEPROP 1 LAST HDL_TAP TRUE
J 0
(-5625 4850);
DISPLAY 0.872340 (-5625 4850);
DISPLAY INVISIBLE (-5625 4850);
FORCEPROP 1 LAST PATH I118
J 0
(-5952 4975);
DISPLAY 0.872340 (-5952 4975);
PAINT GREEN (-5952 4975);
DISPLAY INVISIBLE (-5952 4975);
FORCEADD TAP..1
(-5950 4925);
FORCEPROP 3 LASTPIN (-6000 4925) SIG_NAME M_J_CPU0_SA_DQ<23>
J 0
(-5990 4935);
DISPLAY 0.659574 (-5990 4935);
PAINT MONO (-5990 4935);
DISPLAY INVISIBLE (-5990 4935);
FORCEPROP 1 LASTPIN (-6000 4925) BN 23
J 0
(-6012 4933);
DISPLAY 0.489362 (-6012 4933);
PAINT GREEN (-6012 4933);
FORCEPROP 2 LAST CDS_LIB mstr_standard
J 0
(-5950 4925);
DISPLAY 0.723404 (-5950 4925);
PAINT MONO (-5950 4925);
DISPLAY INVISIBLE (-5950 4925);
FORCEPROP 1 LAST BODY_TYPE PLUMBING
J 0
(-5950 4975);
DISPLAY 0.872340 (-5950 4975);
PAINT GREEN (-5950 4975);
DISPLAY INVISIBLE (-5950 4975);
FORCEPROP 1 LAST HDL_TAP TRUE
J 0
(-5625 4800);
DISPLAY 0.872340 (-5625 4800);
DISPLAY INVISIBLE (-5625 4800);
FORCEPROP 1 LAST PATH I119
J 0
(-5952 4925);
DISPLAY 0.872340 (-5952 4925);
PAINT GREEN (-5952 4925);
DISPLAY INVISIBLE (-5952 4925);
FORCEADD OFFPAGE..1
(-8250 4025);
FORCEPROP 2 LAST $XR0 19 
J 0
(-8501 4025);
DISPLAY 0.638298 (-8501 4025);
PAINT MONO (-8501 4025);
FORCEPROP 2 LAST CDS_LIB mstr_standard
J 0
(-8250 4025);
DISPLAY 0.808511 (-8250 4025);
DISPLAY INVISIBLE (-8250 4025);
FORCEPROP 1 LAST OFFPAGE TRUE
J 0
(-7925 3900);
DISPLAY 0.872340 (-7925 3900);
PAINT GREEN (-7925 3900);
DISPLAY INVISIBLE (-7925 3900);
FORCEPROP 1 LAST COMMENT_BODY TRUE
J 0
(-8125 3925);
DISPLAY 0.872340 (-8125 3925);
PAINT GREEN (-8125 3925);
DISPLAY INVISIBLE (-8125 3925);
FORCEPROP 2 LAST PATH I12
J 0
(-8200 4100);
DISPLAY 1.021277 (-8200 4100);
DISPLAY INVISIBLE (-8200 4100);
FORCEADD TAP..1
(-5950 5125);
FORCEPROP 3 LASTPIN (-6000 5125) SIG_NAME M_J_CPU0_SA_DQ<27>
J 0
(-5990 5135);
DISPLAY 0.659574 (-5990 5135);
PAINT MONO (-5990 5135);
DISPLAY INVISIBLE (-5990 5135);
FORCEPROP 1 LASTPIN (-6000 5125) BN 27
J 0
(-6012 5133);
DISPLAY 0.489362 (-6012 5133);
PAINT GREEN (-6012 5133);
FORCEPROP 2 LAST CDS_LIB mstr_standard
J 0
(-5950 5125);
DISPLAY 0.723404 (-5950 5125);
PAINT MONO (-5950 5125);
DISPLAY INVISIBLE (-5950 5125);
FORCEPROP 1 LAST BODY_TYPE PLUMBING
J 0
(-5950 5175);
DISPLAY 0.872340 (-5950 5175);
PAINT GREEN (-5950 5175);
DISPLAY INVISIBLE (-5950 5175);
FORCEPROP 1 LAST HDL_TAP TRUE
J 0
(-5625 5000);
DISPLAY 0.872340 (-5625 5000);
DISPLAY INVISIBLE (-5625 5000);
FORCEPROP 1 LAST PATH I120
J 0
(-5952 5125);
DISPLAY 0.872340 (-5952 5125);
PAINT GREEN (-5952 5125);
DISPLAY INVISIBLE (-5952 5125);
FORCEADD TAP..1
(-5950 5175);
FORCEPROP 3 LASTPIN (-6000 5175) SIG_NAME M_J_CPU0_SA_DQ<28>
J 0
(-5990 5185);
DISPLAY 0.659574 (-5990 5185);
PAINT MONO (-5990 5185);
DISPLAY INVISIBLE (-5990 5185);
FORCEPROP 1 LASTPIN (-6000 5175) BN 28
J 0
(-6012 5183);
DISPLAY 0.489362 (-6012 5183);
PAINT GREEN (-6012 5183);
FORCEPROP 2 LAST CDS_LIB mstr_standard
J 0
(-5950 5175);
DISPLAY 0.723404 (-5950 5175);
PAINT MONO (-5950 5175);
DISPLAY INVISIBLE (-5950 5175);
FORCEPROP 1 LAST BODY_TYPE PLUMBING
J 0
(-5950 5225);
DISPLAY 0.872340 (-5950 5225);
PAINT GREEN (-5950 5225);
DISPLAY INVISIBLE (-5950 5225);
FORCEPROP 1 LAST HDL_TAP TRUE
J 0
(-5625 5050);
DISPLAY 0.872340 (-5625 5050);
DISPLAY INVISIBLE (-5625 5050);
FORCEPROP 1 LAST PATH I121
J 0
(-5952 5175);
DISPLAY 0.872340 (-5952 5175);
PAINT GREEN (-5952 5175);
DISPLAY INVISIBLE (-5952 5175);
FORCEADD TAP..1
(-5950 5075);
FORCEPROP 3 LASTPIN (-6000 5075) SIG_NAME M_J_CPU0_SA_DQ<26>
J 0
(-5990 5085);
DISPLAY 0.659574 (-5990 5085);
PAINT MONO (-5990 5085);
DISPLAY INVISIBLE (-5990 5085);
FORCEPROP 1 LASTPIN (-6000 5075) BN 26
J 0
(-6012 5083);
DISPLAY 0.489362 (-6012 5083);
PAINT GREEN (-6012 5083);
FORCEPROP 2 LAST CDS_LIB mstr_standard
J 0
(-5950 5075);
DISPLAY 0.723404 (-5950 5075);
PAINT MONO (-5950 5075);
DISPLAY INVISIBLE (-5950 5075);
FORCEPROP 1 LAST BODY_TYPE PLUMBING
J 0
(-5950 5125);
DISPLAY 0.872340 (-5950 5125);
PAINT GREEN (-5950 5125);
DISPLAY INVISIBLE (-5950 5125);
FORCEPROP 1 LAST HDL_TAP TRUE
J 0
(-5625 4950);
DISPLAY 0.872340 (-5625 4950);
DISPLAY INVISIBLE (-5625 4950);
FORCEPROP 1 LAST PATH I122
J 0
(-5952 5075);
DISPLAY 0.872340 (-5952 5075);
PAINT GREEN (-5952 5075);
DISPLAY INVISIBLE (-5952 5075);
FORCEADD TAP..1
(-5950 5275);
FORCEPROP 3 LASTPIN (-6000 5275) SIG_NAME M_J_CPU0_SA_DQ<30>
J 0
(-5990 5285);
DISPLAY 0.659574 (-5990 5285);
PAINT MONO (-5990 5285);
DISPLAY INVISIBLE (-5990 5285);
FORCEPROP 1 LASTPIN (-6000 5275) BN 30
J 0
(-6012 5283);
DISPLAY 0.489362 (-6012 5283);
PAINT GREEN (-6012 5283);
FORCEPROP 2 LAST CDS_LIB mstr_standard
J 0
(-5950 5275);
DISPLAY 0.723404 (-5950 5275);
PAINT MONO (-5950 5275);
DISPLAY INVISIBLE (-5950 5275);
FORCEPROP 1 LAST BODY_TYPE PLUMBING
J 0
(-5950 5325);
DISPLAY 0.872340 (-5950 5325);
PAINT GREEN (-5950 5325);
DISPLAY INVISIBLE (-5950 5325);
FORCEPROP 1 LAST HDL_TAP TRUE
J 0
(-5625 5150);
DISPLAY 0.872340 (-5625 5150);
DISPLAY INVISIBLE (-5625 5150);
FORCEPROP 1 LAST PATH I123
J 0
(-5952 5275);
DISPLAY 0.872340 (-5952 5275);
PAINT GREEN (-5952 5275);
DISPLAY INVISIBLE (-5952 5275);
FORCEADD TAP..1
(-5950 5225);
FORCEPROP 3 LASTPIN (-6000 5225) SIG_NAME M_J_CPU0_SA_DQ<29>
J 0
(-5990 5235);
DISPLAY 0.659574 (-5990 5235);
PAINT MONO (-5990 5235);
DISPLAY INVISIBLE (-5990 5235);
FORCEPROP 1 LASTPIN (-6000 5225) BN 29
J 0
(-6012 5233);
DISPLAY 0.489362 (-6012 5233);
PAINT GREEN (-6012 5233);
FORCEPROP 2 LAST CDS_LIB mstr_standard
J 0
(-5950 5225);
DISPLAY 0.723404 (-5950 5225);
PAINT MONO (-5950 5225);
DISPLAY INVISIBLE (-5950 5225);
FORCEPROP 1 LAST BODY_TYPE PLUMBING
J 0
(-5950 5275);
DISPLAY 0.872340 (-5950 5275);
PAINT GREEN (-5950 5275);
DISPLAY INVISIBLE (-5950 5275);
FORCEPROP 1 LAST HDL_TAP TRUE
J 0
(-5625 5100);
DISPLAY 0.872340 (-5625 5100);
DISPLAY INVISIBLE (-5625 5100);
FORCEPROP 1 LAST PATH I124
J 0
(-5952 5225);
DISPLAY 0.872340 (-5952 5225);
PAINT GREEN (-5952 5225);
DISPLAY INVISIBLE (-5952 5225);
FORCEADD TAP..1
(-5950 5325);
FORCEPROP 3 LASTPIN (-6000 5325) SIG_NAME M_J_CPU0_SA_DQ<31>
J 0
(-5990 5335);
DISPLAY 0.659574 (-5990 5335);
PAINT MONO (-5990 5335);
DISPLAY INVISIBLE (-5990 5335);
FORCEPROP 1 LASTPIN (-6000 5325) BN 31
J 0
(-6012 5333);
DISPLAY 0.489362 (-6012 5333);
PAINT GREEN (-6012 5333);
FORCEPROP 2 LAST CDS_LIB mstr_standard
J 0
(-5950 5325);
DISPLAY 0.723404 (-5950 5325);
PAINT MONO (-5950 5325);
DISPLAY INVISIBLE (-5950 5325);
FORCEPROP 1 LAST BODY_TYPE PLUMBING
J 0
(-5950 5375);
DISPLAY 0.872340 (-5950 5375);
PAINT GREEN (-5950 5375);
DISPLAY INVISIBLE (-5950 5375);
FORCEPROP 1 LAST HDL_TAP TRUE
J 0
(-5625 5200);
DISPLAY 0.872340 (-5625 5200);
DISPLAY INVISIBLE (-5625 5200);
FORCEPROP 1 LAST PATH I125
J 0
(-5952 5325);
DISPLAY 0.872340 (-5952 5325);
PAINT GREEN (-5952 5325);
DISPLAY INVISIBLE (-5952 5325);
FORCEADD OFFPAGE..3
(-5200 5375);
FORCEPROP 2 LAST $XR0 19 
J 0
(-4986 5375);
DISPLAY 0.638298 (-4986 5375);
PAINT MONO (-4986 5375);
FORCEPROP 2 LAST CDS_LIB mstr_standard
J 0
(-5200 5375);
DISPLAY 0.723404 (-5200 5375);
PAINT MONO (-5200 5375);
DISPLAY INVISIBLE (-5200 5375);
FORCEPROP 1 LAST OFFPAGE TRUE
J 0
(-4875 5250);
DISPLAY 0.872340 (-4875 5250);
PAINT GREEN (-4875 5250);
DISPLAY INVISIBLE (-4875 5250);
FORCEPROP 1 LAST COMMENT_BODY TRUE
J 0
(-5250 5275);
DISPLAY 0.872340 (-5250 5275);
PAINT GREEN (-5250 5275);
DISPLAY INVISIBLE (-5250 5275);
FORCEPROP 2 LAST PATH I126
J 0
(-5000 5450);
DISPLAY 1.021277 (-5000 5450);
DISPLAY INVISIBLE (-5000 5450);
FORCEADD OFFPAGE..5
(-7125 1350);
FORCEPROP 2 LAST $XR0 95 
J 0
(-7349 1350);
DISPLAY 0.638298 (-7349 1350);
PAINT MONO (-7349 1350);
FORCEPROP 2 LAST BOM_COST MEM
J 0
(-7200 1425);
DISPLAY 0.808511 (-7200 1425);
DISPLAY INVISIBLE (-7200 1425);
FORCEPROP 2 LAST CDS_LIB mstr_standard
J 0
(-7125 1350);
DISPLAY 0.808511 (-7125 1350);
DISPLAY INVISIBLE (-7125 1350);
FORCEPROP 1 LAST OFFPAGE TRUE
J 0
(-6800 1225);
DISPLAY 0.872340 (-6800 1225);
PAINT GREEN (-6800 1225);
DISPLAY INVISIBLE (-6800 1225);
FORCEPROP 1 LAST COMMENT_BODY TRUE
J 0
(-7025 1275);
DISPLAY 0.872340 (-7025 1275);
PAINT GREEN (-7025 1275);
DISPLAY INVISIBLE (-7025 1275);
FORCEPROP 2 LAST PATH I127
J 0
(-7375 1400);
DISPLAY 1.021277 (-7375 1400);
DISPLAY INVISIBLE (-7375 1400);
FORCEADD GND..1
(-6350 950);
FORCEPROP 3 LASTPIN (-6350 1000) SIG_NAME GND\g
J 0
(-6340 1010);
DISPLAY 0.659574 (-6340 1010);
PAINT MONO (-6340 1010);
DISPLAY INVISIBLE (-6340 1010);
FORCEPROP 1 LAST SIZE 1B
J 0
(-6275 900);
DISPLAY 0.851064 (-6275 900);
PAINT GREEN (-6275 900);
DISPLAY INVISIBLE (-6275 900);
FORCEPROP 2 LAST BOM_COST MEM
J 0
(-6450 1025);
DISPLAY 0.808511 (-6450 1025);
DISPLAY INVISIBLE (-6450 1025);
FORCEPROP 2 LAST CDS_LIB mstr_symbols
J 0
(-6350 950);
DISPLAY 0.808511 (-6350 950);
DISPLAY INVISIBLE (-6350 950);
FORCEPROP 1 LAST VOLTAGE 0.0
J 0
(-6395 907);
DISPLAY 0.723404 (-6395 907);
PAINT SKYBLUE (-6395 907);
DISPLAY INVISIBLE (-6395 907);
FORCEPROP 1 LAST BODY_TYPE PLUMBING
J 0
(-6395 907);
DISPLAY 0.340426 (-6395 907);
PAINT GREEN (-6395 907);
DISPLAY INVISIBLE (-6395 907);
FORCEPROP 1 LAST HDL_POWER GND
J 0
(-6350 1100);
DISPLAY 0.851064 (-6350 1100);
PAINT GREEN (-6350 1100);
DISPLAY INVISIBLE (-6350 1100);
FORCEPROP 1 LAST PATH I128
J 0
(-6275 950);
DISPLAY 0.872340 (-6275 950);
PAINT AQUA (-6275 950);
DISPLAY INVISIBLE (-6275 950);
FORCEADD Q_RES..2
(-6350 1175);
FORCEPROP 1 LAST LOCATION R767
J 0
(-6305 1300);
DISPLAY 0.489362 (-6305 1300);
PAINT SKYBLUE (-6305 1300);
FORCEPROP 0 LAST $SEC 1
J 0
(-6300 1350);
DISPLAY 0.680851 (-6300 1350);
PAINT MONO (-6300 1350);
DISPLAY INVISIBLE (-6300 1350);
FORCEPROP 0 LAST CDS_SEC 1
J 0
(-6300 1350);
DISPLAY 1.021277 (-6300 1350);
DISPLAY INVISIBLE (-6300 1350);
FORCEPROP 1 LASTPIN (-6350 1275) $PN 1
J 0
(-6345 1237);
DISPLAY 0.489362 (-6345 1237);
PAINT MONO (-6345 1237);
FORCEPROP 1 LASTPIN (-6350 1075) $PN 2
J 0
(-6345 1085);
DISPLAY 0.489362 (-6345 1085);
PAINT MONO (-6345 1085);
FORCEPROP 1 LAST WATTAGE 1/16W
J 0
(-6310 1150);
DISPLAY 0.489362 (-6310 1150);
PAINT SKYBLUE (-6310 1150);
FORCEPROP 1 LAST MATERIAL CHIP
J 0
(-6310 1100);
DISPLAY 0.489362 (-6310 1100);
PAINT SKYBLUE (-6310 1100);
FORCEPROP 1 LAST TOLERANCE 1%
J 0
(-6305 1200);
DISPLAY 0.489362 (-6305 1200);
PAINT SKYBLUE (-6305 1200);
FORCEPROP 1 LAST VALUE 35.7K
J 0
(-6305 1250);
DISPLAY 0.489362 (-6305 1250);
PAINT SKYBLUE (-6305 1250);
FORCEPROP 1 LAST PACK_TYPE 0402LF
J 0
(-6310 1000);
DISPLAY 0.489362 (-6310 1000);
PAINT SKYBLUE (-6310 1000);
FORCEPROP 2 LAST CDS_LIB pure_quanta
J 0
(-6350 1175);
DISPLAY INVISIBLE (-6350 1175);
FORCEPROP 1 LAST PATH I129
J 0
(-6300 1350);
DISPLAY 0.978723 (-6300 1350);
PAINT WHITE (-6300 1350);
DISPLAY INVISIBLE (-6300 1350);
FORCEPROP 1 LAST PART_NUMBER CS33572FB01
J 0
(-6310 1050);
DISPLAY 0.489362 (-6310 1050);
PAINT SKYBLUE (-6310 1050);
DISPLAY INVISIBLE (-6310 1050);
FORCEADD OFFPAGE..1
(-8250 4225);
FORCEPROP 2 LAST $XR0 19 
J 0
(-8501 4225);
DISPLAY 0.638298 (-8501 4225);
PAINT MONO (-8501 4225);
FORCEPROP 2 LAST CDS_LIB mstr_standard
J 0
(-8250 4225);
DISPLAY 0.723404 (-8250 4225);
PAINT MONO (-8250 4225);
DISPLAY INVISIBLE (-8250 4225);
FORCEPROP 1 LAST OFFPAGE TRUE
J 0
(-7925 4100);
DISPLAY 0.872340 (-7925 4100);
PAINT GREEN (-7925 4100);
DISPLAY INVISIBLE (-7925 4100);
FORCEPROP 1 LAST COMMENT_BODY TRUE
J 0
(-8125 4125);
DISPLAY 0.872340 (-8125 4125);
PAINT GREEN (-8125 4125);
DISPLAY INVISIBLE (-8125 4125);
FORCEPROP 2 LAST PATH I13
J 0
(-8200 4300);
DISPLAY 1.021277 (-8200 4300);
DISPLAY INVISIBLE (-8200 4300);
FORCEADD OFFPAGE..1
(-8250 4175);
FORCEPROP 2 LAST $XR0 19 
J 0
(-8501 4175);
DISPLAY 0.638298 (-8501 4175);
PAINT MONO (-8501 4175);
FORCEPROP 2 LAST CDS_LIB mstr_standard
J 0
(-8250 4175);
DISPLAY 0.808511 (-8250 4175);
DISPLAY INVISIBLE (-8250 4175);
FORCEPROP 1 LAST OFFPAGE TRUE
J 0
(-7925 4050);
DISPLAY 0.872340 (-7925 4050);
PAINT GREEN (-7925 4050);
DISPLAY INVISIBLE (-7925 4050);
FORCEPROP 1 LAST COMMENT_BODY TRUE
J 0
(-8125 4075);
DISPLAY 0.872340 (-8125 4075);
PAINT GREEN (-8125 4075);
DISPLAY INVISIBLE (-8125 4075);
FORCEPROP 2 LAST PATH I14
J 0
(-8200 4250);
DISPLAY 1.021277 (-8200 4250);
DISPLAY INVISIBLE (-8200 4250);
FORCEADD GND..1
(-2050 1850);
FORCEPROP 3 LASTPIN (-2050 1900) SIG_NAME GND\g
J 0
(-2040 1910);
DISPLAY 0.659574 (-2040 1910);
PAINT MONO (-2040 1910);
DISPLAY INVISIBLE (-2040 1910);
FORCEPROP 1 LAST SIZE 1B
J 0
(-1975 1800);
DISPLAY 0.851064 (-1975 1800);
PAINT GREEN (-1975 1800);
DISPLAY INVISIBLE (-1975 1800);
FORCEPROP 2 LAST CDS_LIB mstr_symbols
J 0
(-2050 1850);
DISPLAY 0.723404 (-2050 1850);
DISPLAY INVISIBLE (-2050 1850);
FORCEPROP 1 LAST VOLTAGE 0.0
J 0
(-2095 1807);
DISPLAY 0.723404 (-2095 1807);
PAINT SKYBLUE (-2095 1807);
DISPLAY INVISIBLE (-2095 1807);
FORCEPROP 1 LAST BODY_TYPE PLUMBING
J 0
(-2095 1807);
DISPLAY 0.340426 (-2095 1807);
PAINT GREEN (-2095 1807);
DISPLAY INVISIBLE (-2095 1807);
FORCEPROP 1 LAST HDL_POWER GND
J 0
(-2050 2000);
DISPLAY 0.851064 (-2050 2000);
PAINT GREEN (-2050 2000);
DISPLAY INVISIBLE (-2050 2000);
FORCEPROP 1 LAST PATH I141
J 0
(-1975 1850);
DISPLAY 0.872340 (-1975 1850);
PAINT AQUA (-1975 1850);
DISPLAY INVISIBLE (-1975 1850);
FORCEADD GND..1
(-250 1625);
FORCEPROP 3 LASTPIN (-250 1675) SIG_NAME GND\g
J 0
(-240 1685);
DISPLAY 0.659574 (-240 1685);
PAINT MONO (-240 1685);
DISPLAY INVISIBLE (-240 1685);
FORCEPROP 2 LAST CDS_LIB mstr_symbols
J 0
(-250 1625);
DISPLAY 0.723404 (-250 1625);
DISPLAY INVISIBLE (-250 1625);
FORCEPROP 1 LAST SIZE 1B
J 0
(-175 1575);
DISPLAY 0.851064 (-175 1575);
PAINT GREEN (-175 1575);
DISPLAY INVISIBLE (-175 1575);
FORCEPROP 1 LAST VOLTAGE 0.0
J 0
(-295 1582);
DISPLAY 0.723404 (-295 1582);
PAINT SKYBLUE (-295 1582);
DISPLAY INVISIBLE (-295 1582);
FORCEPROP 1 LAST BODY_TYPE PLUMBING
J 0
(-295 1582);
DISPLAY 0.340426 (-295 1582);
PAINT GREEN (-295 1582);
DISPLAY INVISIBLE (-295 1582);
FORCEPROP 1 LAST HDL_POWER GND
J 0
(-250 1775);
DISPLAY 0.851064 (-250 1775);
PAINT GREEN (-250 1775);
DISPLAY INVISIBLE (-250 1775);
FORCEPROP 1 LAST PATH I142
J 0
(-175 1625);
DISPLAY 0.872340 (-175 1625);
PAINT AQUA (-175 1625);
DISPLAY INVISIBLE (-175 1625);
FORCEADD OFFPAGE..1
(-8250 4075);
FORCEPROP 2 LAST $XR0 19 
J 0
(-8501 4075);
DISPLAY 0.638298 (-8501 4075);
PAINT MONO (-8501 4075);
FORCEPROP 2 LAST CDS_LIB mstr_standard
J 0
(-8250 4075);
DISPLAY 0.723404 (-8250 4075);
PAINT MONO (-8250 4075);
DISPLAY INVISIBLE (-8250 4075);
FORCEPROP 1 LAST OFFPAGE TRUE
J 0
(-7925 3950);
DISPLAY 0.872340 (-7925 3950);
PAINT GREEN (-7925 3950);
DISPLAY INVISIBLE (-7925 3950);
FORCEPROP 1 LAST COMMENT_BODY TRUE
J 0
(-8125 3975);
DISPLAY 0.872340 (-8125 3975);
PAINT GREEN (-8125 3975);
DISPLAY INVISIBLE (-8125 3975);
FORCEPROP 2 LAST PATH I15
J 0
(-8200 4150);
DISPLAY 1.021277 (-8200 4150);
DISPLAY INVISIBLE (-8200 4150);
FORCEADD OFFPAGE..1
(-8250 4525);
FORCEPROP 2 LAST $XR0 19 
J 0
(-8501 4525);
DISPLAY 0.638298 (-8501 4525);
PAINT MONO (-8501 4525);
FORCEPROP 2 LAST CDS_LIB mstr_standard
J 0
(-8250 4525);
DISPLAY 0.723404 (-8250 4525);
PAINT MONO (-8250 4525);
DISPLAY INVISIBLE (-8250 4525);
FORCEPROP 1 LAST OFFPAGE TRUE
J 0
(-7925 4400);
DISPLAY 0.872340 (-7925 4400);
PAINT GREEN (-7925 4400);
DISPLAY INVISIBLE (-7925 4400);
FORCEPROP 1 LAST COMMENT_BODY TRUE
J 0
(-8125 4425);
DISPLAY 0.872340 (-8125 4425);
PAINT GREEN (-8125 4425);
DISPLAY INVISIBLE (-8125 4425);
FORCEPROP 2 LAST PATH I16
J 0
(-8200 4600);
DISPLAY 1.021277 (-8200 4600);
DISPLAY INVISIBLE (-8200 4600);
FORCEADD OFFPAGE..1
(-8250 4375);
FORCEPROP 2 LAST $XR0 19 
J 0
(-8501 4375);
DISPLAY 0.638298 (-8501 4375);
PAINT MONO (-8501 4375);
FORCEPROP 2 LAST CDS_LIB mstr_standard
J 0
(-8250 4375);
DISPLAY 0.723404 (-8250 4375);
PAINT MONO (-8250 4375);
DISPLAY INVISIBLE (-8250 4375);
FORCEPROP 1 LAST OFFPAGE TRUE
J 0
(-7925 4250);
DISPLAY 0.872340 (-7925 4250);
PAINT GREEN (-7925 4250);
DISPLAY INVISIBLE (-7925 4250);
FORCEPROP 1 LAST COMMENT_BODY TRUE
J 0
(-8125 4275);
DISPLAY 0.872340 (-8125 4275);
PAINT GREEN (-8125 4275);
DISPLAY INVISIBLE (-8125 4275);
FORCEPROP 2 LAST PATH I17
J 0
(-8200 4450);
DISPLAY 1.021277 (-8200 4450);
DISPLAY INVISIBLE (-8200 4450);
FORCEADD SCONN288_DDR506112002KQ..3
(-1150 3625);
FORCEPROP 1 LAST LOCATION J68
J 0
(-1600 5600);
DISPLAY 0.468085 (-1600 5600);
PAINT SKYBLUE (-1600 5600);
FORCEPROP 0 LAST $SEC 3
J 0
(-1600 5750);
DISPLAY 0.680851 (-1600 5750);
PAINT MONO (-1600 5750);
DISPLAY INVISIBLE (-1600 5750);
FORCEPROP 2 LAST CDS_SEC 3
J 0
(-1600 5750);
DISPLAY 1.021277 (-1600 5750);
DISPLAY INVISIBLE (-1600 5750);
FORCEPROP 0 LASTPIN (-550 2025) $PN G1
J 0
(-540 2035);
DISPLAY 0.680851 (-540 2035);
PAINT MONO (-540 2035);
FORCEPROP 0 LASTPIN (-550 1975) $PN G2
J 0
(-540 1985);
DISPLAY 0.680851 (-540 1985);
PAINT MONO (-540 1985);
FORCEPROP 0 LASTPIN (-550 1925) $PN G3
J 0
(-540 1935);
DISPLAY 0.680851 (-540 1935);
PAINT MONO (-540 1935);
FORCEPROP 0 LASTPIN (-1750 5175) $PN 1
J 2
(-1760 5185);
DISPLAY 0.680851 (-1760 5185);
PAINT MONO (-1760 5185);
FORCEPROP 0 LASTPIN (-1750 5225) $PN 145
J 2
(-1760 5235);
DISPLAY 0.680851 (-1760 5235);
PAINT MONO (-1760 5235);
FORCEPROP 0 LASTPIN (-1750 5275) $PN 146
J 2
(-1760 5285);
DISPLAY 0.680851 (-1760 5285);
PAINT MONO (-1760 5285);
FORCEPROP 0 LASTPIN (-550 2125) $PN 6
J 0
(-540 2135);
DISPLAY 0.680851 (-540 2135);
PAINT MONO (-540 2135);
FORCEPROP 0 LASTPIN (-550 2175) $PN 8
J 0
(-540 2185);
DISPLAY 0.680851 (-540 2185);
PAINT MONO (-540 2185);
FORCEPROP 0 LASTPIN (-550 2225) $PN 10
J 0
(-540 2235);
DISPLAY 0.680851 (-540 2235);
PAINT MONO (-540 2235);
FORCEPROP 0 LASTPIN (-550 2275) $PN 13
J 0
(-540 2285);
DISPLAY 0.680851 (-540 2285);
PAINT MONO (-540 2285);
FORCEPROP 0 LASTPIN (-550 2325) $PN 15
J 0
(-540 2335);
DISPLAY 0.680851 (-540 2335);
PAINT MONO (-540 2335);
FORCEPROP 0 LASTPIN (-550 2375) $PN 17
J 0
(-540 2385);
DISPLAY 0.680851 (-540 2385);
PAINT MONO (-540 2385);
FORCEPROP 0 LASTPIN (-550 2425) $PN 19
J 0
(-540 2435);
DISPLAY 0.680851 (-540 2435);
PAINT MONO (-540 2435);
FORCEPROP 0 LASTPIN (-550 2475) $PN 21
J 0
(-540 2485);
DISPLAY 0.680851 (-540 2485);
PAINT MONO (-540 2485);
FORCEPROP 0 LASTPIN (-550 2525) $PN 24
J 0
(-540 2535);
DISPLAY 0.680851 (-540 2535);
PAINT MONO (-540 2535);
FORCEPROP 0 LASTPIN (-550 2575) $PN 26
J 0
(-540 2585);
DISPLAY 0.680851 (-540 2585);
PAINT MONO (-540 2585);
FORCEPROP 0 LASTPIN (-550 2625) $PN 28
J 0
(-540 2635);
DISPLAY 0.680851 (-540 2635);
PAINT MONO (-540 2635);
FORCEPROP 0 LASTPIN (-550 2675) $PN 30
J 0
(-540 2685);
DISPLAY 0.680851 (-540 2685);
PAINT MONO (-540 2685);
FORCEPROP 0 LASTPIN (-550 2725) $PN 32
J 0
(-540 2735);
DISPLAY 0.680851 (-540 2735);
PAINT MONO (-540 2735);
FORCEPROP 0 LASTPIN (-550 2775) $PN 35
J 0
(-540 2785);
DISPLAY 0.680851 (-540 2785);
PAINT MONO (-540 2785);
FORCEPROP 0 LASTPIN (-550 2825) $PN 37
J 0
(-540 2835);
DISPLAY 0.680851 (-540 2835);
PAINT MONO (-540 2835);
FORCEPROP 0 LASTPIN (-550 2875) $PN 39
J 0
(-540 2885);
DISPLAY 0.680851 (-540 2885);
PAINT MONO (-540 2885);
FORCEPROP 0 LASTPIN (-550 2925) $PN 41
J 0
(-540 2935);
DISPLAY 0.680851 (-540 2935);
PAINT MONO (-540 2935);
FORCEPROP 0 LASTPIN (-550 2975) $PN 43
J 0
(-540 2985);
DISPLAY 0.680851 (-540 2985);
PAINT MONO (-540 2985);
FORCEPROP 0 LASTPIN (-550 3025) $PN 46
J 0
(-540 3035);
DISPLAY 0.680851 (-540 3035);
PAINT MONO (-540 3035);
FORCEPROP 0 LASTPIN (-550 3075) $PN 48
J 0
(-540 3085);
DISPLAY 0.680851 (-540 3085);
PAINT MONO (-540 3085);
FORCEPROP 0 LASTPIN (-550 3125) $PN 50
J 0
(-540 3135);
DISPLAY 0.680851 (-540 3135);
PAINT MONO (-540 3135);
FORCEPROP 0 LASTPIN (-550 3175) $PN 52
J 0
(-540 3185);
DISPLAY 0.680851 (-540 3185);
PAINT MONO (-540 3185);
FORCEPROP 0 LASTPIN (-550 3225) $PN 54
J 0
(-540 3235);
DISPLAY 0.680851 (-540 3235);
PAINT MONO (-540 3235);
FORCEPROP 0 LASTPIN (-550 3275) $PN 57
J 0
(-540 3285);
DISPLAY 0.680851 (-540 3285);
PAINT MONO (-540 3285);
FORCEPROP 0 LASTPIN (-550 3325) $PN 59
J 0
(-540 3335);
DISPLAY 0.680851 (-540 3335);
PAINT MONO (-540 3335);
FORCEPROP 0 LASTPIN (-550 3375) $PN 61
J 0
(-540 3385);
DISPLAY 0.680851 (-540 3385);
PAINT MONO (-540 3385);
FORCEPROP 0 LASTPIN (-550 3425) $PN 63
J 0
(-540 3435);
DISPLAY 0.680851 (-540 3435);
PAINT MONO (-540 3435);
FORCEPROP 0 LASTPIN (-550 3475) $PN 65
J 0
(-540 3485);
DISPLAY 0.680851 (-540 3485);
PAINT MONO (-540 3485);
FORCEPROP 0 LASTPIN (-550 3525) $PN 67
J 0
(-540 3535);
DISPLAY 0.680851 (-540 3535);
PAINT MONO (-540 3535);
FORCEPROP 0 LASTPIN (-550 3575) $PN 69
J 0
(-540 3585);
DISPLAY 0.680851 (-540 3585);
PAINT MONO (-540 3585);
FORCEPROP 0 LASTPIN (-550 3625) $PN 71
J 0
(-540 3635);
DISPLAY 0.680851 (-540 3635);
PAINT MONO (-540 3635);
FORCEPROP 0 LASTPIN (-550 3675) $PN 73
J 0
(-540 3685);
DISPLAY 0.680851 (-540 3685);
PAINT MONO (-540 3685);
FORCEPROP 0 LASTPIN (-550 3725) $PN 75
J 0
(-540 3735);
DISPLAY 0.680851 (-540 3735);
PAINT MONO (-540 3735);
FORCEPROP 0 LASTPIN (-550 3775) $PN 77
J 0
(-540 3785);
DISPLAY 0.680851 (-540 3785);
PAINT MONO (-540 3785);
FORCEPROP 0 LASTPIN (-550 3825) $PN 79
J 0
(-540 3835);
DISPLAY 0.680851 (-540 3835);
PAINT MONO (-540 3835);
FORCEPROP 0 LASTPIN (-550 3875) $PN 81
J 0
(-540 3885);
DISPLAY 0.680851 (-540 3885);
PAINT MONO (-540 3885);
FORCEPROP 0 LASTPIN (-550 3925) $PN 83
J 0
(-540 3935);
DISPLAY 0.680851 (-540 3935);
PAINT MONO (-540 3935);
FORCEPROP 0 LASTPIN (-550 3975) $PN 85
J 0
(-540 3985);
DISPLAY 0.680851 (-540 3985);
PAINT MONO (-540 3985);
FORCEPROP 0 LASTPIN (-550 4025) $PN 88
J 0
(-540 4035);
DISPLAY 0.680851 (-540 4035);
PAINT MONO (-540 4035);
FORCEPROP 0 LASTPIN (-550 4075) $PN 90
J 0
(-540 4085);
DISPLAY 0.680851 (-540 4085);
PAINT MONO (-540 4085);
FORCEPROP 0 LASTPIN (-550 4125) $PN 92
J 0
(-540 4135);
DISPLAY 0.680851 (-540 4135);
PAINT MONO (-540 4135);
FORCEPROP 0 LASTPIN (-550 4175) $PN 95
J 0
(-540 4185);
DISPLAY 0.680851 (-540 4185);
PAINT MONO (-540 4185);
FORCEPROP 0 LASTPIN (-550 4225) $PN 97
J 0
(-540 4235);
DISPLAY 0.680851 (-540 4235);
PAINT MONO (-540 4235);
FORCEPROP 0 LASTPIN (-550 4275) $PN 99
J 0
(-540 4285);
DISPLAY 0.680851 (-540 4285);
PAINT MONO (-540 4285);
FORCEPROP 0 LASTPIN (-550 4325) $PN 101
J 0
(-540 4335);
DISPLAY 0.680851 (-540 4335);
PAINT MONO (-540 4335);
FORCEPROP 0 LASTPIN (-550 4375) $PN 103
J 0
(-540 4385);
DISPLAY 0.680851 (-540 4385);
PAINT MONO (-540 4385);
FORCEPROP 0 LASTPIN (-550 4425) $PN 106
J 0
(-540 4435);
DISPLAY 0.680851 (-540 4435);
PAINT MONO (-540 4435);
FORCEPROP 0 LASTPIN (-550 4475) $PN 108
J 0
(-540 4485);
DISPLAY 0.680851 (-540 4485);
PAINT MONO (-540 4485);
FORCEPROP 0 LASTPIN (-550 4525) $PN 110
J 0
(-540 4535);
DISPLAY 0.680851 (-540 4535);
PAINT MONO (-540 4535);
FORCEPROP 0 LASTPIN (-550 4575) $PN 112
J 0
(-540 4585);
DISPLAY 0.680851 (-540 4585);
PAINT MONO (-540 4585);
FORCEPROP 0 LASTPIN (-550 4625) $PN 114
J 0
(-540 4635);
DISPLAY 0.680851 (-540 4635);
PAINT MONO (-540 4635);
FORCEPROP 0 LASTPIN (-550 4675) $PN 117
J 0
(-540 4685);
DISPLAY 0.680851 (-540 4685);
PAINT MONO (-540 4685);
FORCEPROP 0 LASTPIN (-550 4725) $PN 119
J 0
(-540 4735);
DISPLAY 0.680851 (-540 4735);
PAINT MONO (-540 4735);
FORCEPROP 0 LASTPIN (-550 4775) $PN 121
J 0
(-540 4785);
DISPLAY 0.680851 (-540 4785);
PAINT MONO (-540 4785);
FORCEPROP 0 LASTPIN (-550 4825) $PN 123
J 0
(-540 4835);
DISPLAY 0.680851 (-540 4835);
PAINT MONO (-540 4835);
FORCEPROP 0 LASTPIN (-550 4875) $PN 125
J 0
(-540 4885);
DISPLAY 0.680851 (-540 4885);
PAINT MONO (-540 4885);
FORCEPROP 0 LASTPIN (-550 4925) $PN 128
J 0
(-540 4935);
DISPLAY 0.680851 (-540 4935);
PAINT MONO (-540 4935);
FORCEPROP 0 LASTPIN (-550 4975) $PN 130
J 0
(-540 4985);
DISPLAY 0.680851 (-540 4985);
PAINT MONO (-540 4985);
FORCEPROP 0 LASTPIN (-550 5025) $PN 132
J 0
(-540 5035);
DISPLAY 0.680851 (-540 5035);
PAINT MONO (-540 5035);
FORCEPROP 0 LASTPIN (-550 5075) $PN 134
J 0
(-540 5085);
DISPLAY 0.680851 (-540 5085);
PAINT MONO (-540 5085);
FORCEPROP 0 LASTPIN (-550 5125) $PN 136
J 0
(-540 5135);
DISPLAY 0.680851 (-540 5135);
PAINT MONO (-540 5135);
FORCEPROP 0 LASTPIN (-550 5175) $PN 139
J 0
(-540 5185);
DISPLAY 0.680851 (-540 5185);
PAINT MONO (-540 5185);
FORCEPROP 0 LASTPIN (-550 5225) $PN 141
J 0
(-540 5235);
DISPLAY 0.680851 (-540 5235);
PAINT MONO (-540 5235);
FORCEPROP 0 LASTPIN (-550 5275) $PN 143
J 0
(-540 5285);
DISPLAY 0.680851 (-540 5285);
PAINT MONO (-540 5285);
FORCEPROP 0 LASTPIN (-1750 2025) $PN 151
J 2
(-1760 2035);
DISPLAY 0.680851 (-1760 2035);
PAINT MONO (-1760 2035);
FORCEPROP 0 LASTPIN (-1750 2075) $PN 153
J 2
(-1760 2085);
DISPLAY 0.680851 (-1760 2085);
PAINT MONO (-1760 2085);
FORCEPROP 0 LASTPIN (-1750 2125) $PN 155
J 2
(-1760 2135);
DISPLAY 0.680851 (-1760 2135);
PAINT MONO (-1760 2135);
FORCEPROP 0 LASTPIN (-1750 2175) $PN 158
J 2
(-1760 2185);
DISPLAY 0.680851 (-1760 2185);
PAINT MONO (-1760 2185);
FORCEPROP 0 LASTPIN (-1750 2225) $PN 160
J 2
(-1760 2235);
DISPLAY 0.680851 (-1760 2235);
PAINT MONO (-1760 2235);
FORCEPROP 0 LASTPIN (-1750 2275) $PN 162
J 2
(-1760 2285);
DISPLAY 0.680851 (-1760 2285);
PAINT MONO (-1760 2285);
FORCEPROP 0 LASTPIN (-1750 2325) $PN 164
J 2
(-1760 2335);
DISPLAY 0.680851 (-1760 2335);
PAINT MONO (-1760 2335);
FORCEPROP 0 LASTPIN (-1750 2375) $PN 166
J 2
(-1760 2385);
DISPLAY 0.680851 (-1760 2385);
PAINT MONO (-1760 2385);
FORCEPROP 0 LASTPIN (-1750 2425) $PN 169
J 2
(-1760 2435);
DISPLAY 0.680851 (-1760 2435);
PAINT MONO (-1760 2435);
FORCEPROP 0 LASTPIN (-1750 2475) $PN 171
J 2
(-1760 2485);
DISPLAY 0.680851 (-1760 2485);
PAINT MONO (-1760 2485);
FORCEPROP 0 LASTPIN (-1750 2525) $PN 173
J 2
(-1760 2535);
DISPLAY 0.680851 (-1760 2535);
PAINT MONO (-1760 2535);
FORCEPROP 0 LASTPIN (-1750 2575) $PN 175
J 2
(-1760 2585);
DISPLAY 0.680851 (-1760 2585);
PAINT MONO (-1760 2585);
FORCEPROP 0 LASTPIN (-1750 2625) $PN 177
J 2
(-1760 2635);
DISPLAY 0.680851 (-1760 2635);
PAINT MONO (-1760 2635);
FORCEPROP 0 LASTPIN (-1750 2675) $PN 180
J 2
(-1760 2685);
DISPLAY 0.680851 (-1760 2685);
PAINT MONO (-1760 2685);
FORCEPROP 0 LASTPIN (-1750 2725) $PN 182
J 2
(-1760 2735);
DISPLAY 0.680851 (-1760 2735);
PAINT MONO (-1760 2735);
FORCEPROP 0 LASTPIN (-1750 2775) $PN 184
J 2
(-1760 2785);
DISPLAY 0.680851 (-1760 2785);
PAINT MONO (-1760 2785);
FORCEPROP 0 LASTPIN (-1750 2825) $PN 186
J 2
(-1760 2835);
DISPLAY 0.680851 (-1760 2835);
PAINT MONO (-1760 2835);
FORCEPROP 0 LASTPIN (-1750 2875) $PN 188
J 2
(-1760 2885);
DISPLAY 0.680851 (-1760 2885);
PAINT MONO (-1760 2885);
FORCEPROP 0 LASTPIN (-1750 2925) $PN 191
J 2
(-1760 2935);
DISPLAY 0.680851 (-1760 2935);
PAINT MONO (-1760 2935);
FORCEPROP 0 LASTPIN (-1750 2975) $PN 193
J 2
(-1760 2985);
DISPLAY 0.680851 (-1760 2985);
PAINT MONO (-1760 2985);
FORCEPROP 0 LASTPIN (-1750 3025) $PN 195
J 2
(-1760 3035);
DISPLAY 0.680851 (-1760 3035);
PAINT MONO (-1760 3035);
FORCEPROP 0 LASTPIN (-1750 3075) $PN 197
J 2
(-1760 3085);
DISPLAY 0.680851 (-1760 3085);
PAINT MONO (-1760 3085);
FORCEPROP 0 LASTPIN (-1750 3125) $PN 199
J 2
(-1760 3135);
DISPLAY 0.680851 (-1760 3135);
PAINT MONO (-1760 3135);
FORCEPROP 0 LASTPIN (-1750 3175) $PN 202
J 2
(-1760 3185);
DISPLAY 0.680851 (-1760 3185);
PAINT MONO (-1760 3185);
FORCEPROP 0 LASTPIN (-1750 3225) $PN 204
J 2
(-1760 3235);
DISPLAY 0.680851 (-1760 3235);
PAINT MONO (-1760 3235);
FORCEPROP 0 LASTPIN (-1750 3275) $PN 206
J 2
(-1760 3285);
DISPLAY 0.680851 (-1760 3285);
PAINT MONO (-1760 3285);
FORCEPROP 0 LASTPIN (-1750 3325) $PN 208
J 2
(-1760 3335);
DISPLAY 0.680851 (-1760 3335);
PAINT MONO (-1760 3335);
FORCEPROP 0 LASTPIN (-1750 3375) $PN 210
J 2
(-1760 3385);
DISPLAY 0.680851 (-1760 3385);
PAINT MONO (-1760 3385);
FORCEPROP 0 LASTPIN (-1750 3425) $PN 212
J 2
(-1760 3435);
DISPLAY 0.680851 (-1760 3435);
PAINT MONO (-1760 3435);
FORCEPROP 0 LASTPIN (-1750 3475) $PN 214
J 2
(-1760 3485);
DISPLAY 0.680851 (-1760 3485);
PAINT MONO (-1760 3485);
FORCEPROP 0 LASTPIN (-1750 3525) $PN 216
J 2
(-1760 3535);
DISPLAY 0.680851 (-1760 3535);
PAINT MONO (-1760 3535);
FORCEPROP 0 LASTPIN (-1750 3575) $PN 219
J 2
(-1760 3585);
DISPLAY 0.680851 (-1760 3585);
PAINT MONO (-1760 3585);
FORCEPROP 0 LASTPIN (-1750 3625) $PN 222
J 2
(-1760 3635);
DISPLAY 0.680851 (-1760 3635);
PAINT MONO (-1760 3635);
FORCEPROP 0 LASTPIN (-1750 3675) $PN 224
J 2
(-1760 3685);
DISPLAY 0.680851 (-1760 3685);
PAINT MONO (-1760 3685);
FORCEPROP 0 LASTPIN (-1750 3725) $PN 226
J 2
(-1760 3735);
DISPLAY 0.680851 (-1760 3735);
PAINT MONO (-1760 3735);
FORCEPROP 0 LASTPIN (-1750 3775) $PN 228
J 2
(-1760 3785);
DISPLAY 0.680851 (-1760 3785);
PAINT MONO (-1760 3785);
FORCEPROP 0 LASTPIN (-1750 3825) $PN 230
J 2
(-1760 3835);
DISPLAY 0.680851 (-1760 3835);
PAINT MONO (-1760 3835);
FORCEPROP 0 LASTPIN (-1750 3875) $PN 233
J 2
(-1760 3885);
DISPLAY 0.680851 (-1760 3885);
PAINT MONO (-1760 3885);
FORCEPROP 0 LASTPIN (-1750 3925) $PN 235
J 2
(-1760 3935);
DISPLAY 0.680851 (-1760 3935);
PAINT MONO (-1760 3935);
FORCEPROP 0 LASTPIN (-1750 3975) $PN 237
J 2
(-1760 3985);
DISPLAY 0.680851 (-1760 3985);
PAINT MONO (-1760 3985);
FORCEPROP 0 LASTPIN (-1750 4025) $PN 240
J 2
(-1760 4035);
DISPLAY 0.680851 (-1760 4035);
PAINT MONO (-1760 4035);
FORCEPROP 0 LASTPIN (-1750 4075) $PN 242
J 2
(-1760 4085);
DISPLAY 0.680851 (-1760 4085);
PAINT MONO (-1760 4085);
FORCEPROP 0 LASTPIN (-1750 4125) $PN 244
J 2
(-1760 4135);
DISPLAY 0.680851 (-1760 4135);
PAINT MONO (-1760 4135);
FORCEPROP 0 LASTPIN (-1750 4175) $PN 246
J 2
(-1760 4185);
DISPLAY 0.680851 (-1760 4185);
PAINT MONO (-1760 4185);
FORCEPROP 0 LASTPIN (-1750 4225) $PN 248
J 2
(-1760 4235);
DISPLAY 0.680851 (-1760 4235);
PAINT MONO (-1760 4235);
FORCEPROP 0 LASTPIN (-1750 4275) $PN 251
J 2
(-1760 4285);
DISPLAY 0.680851 (-1760 4285);
PAINT MONO (-1760 4285);
FORCEPROP 0 LASTPIN (-1750 4325) $PN 253
J 2
(-1760 4335);
DISPLAY 0.680851 (-1760 4335);
PAINT MONO (-1760 4335);
FORCEPROP 0 LASTPIN (-1750 4375) $PN 255
J 2
(-1760 4385);
DISPLAY 0.680851 (-1760 4385);
PAINT MONO (-1760 4385);
FORCEPROP 0 LASTPIN (-1750 4425) $PN 257
J 2
(-1760 4435);
DISPLAY 0.680851 (-1760 4435);
PAINT MONO (-1760 4435);
FORCEPROP 0 LASTPIN (-1750 4475) $PN 259
J 2
(-1760 4485);
DISPLAY 0.680851 (-1760 4485);
PAINT MONO (-1760 4485);
FORCEPROP 0 LASTPIN (-1750 4525) $PN 262
J 2
(-1760 4535);
DISPLAY 0.680851 (-1760 4535);
PAINT MONO (-1760 4535);
FORCEPROP 0 LASTPIN (-1750 4575) $PN 264
J 2
(-1760 4585);
DISPLAY 0.680851 (-1760 4585);
PAINT MONO (-1760 4585);
FORCEPROP 0 LASTPIN (-1750 4625) $PN 266
J 2
(-1760 4635);
DISPLAY 0.680851 (-1760 4635);
PAINT MONO (-1760 4635);
FORCEPROP 0 LASTPIN (-1750 4675) $PN 268
J 2
(-1760 4685);
DISPLAY 0.680851 (-1760 4685);
PAINT MONO (-1760 4685);
FORCEPROP 0 LASTPIN (-1750 4725) $PN 270
J 2
(-1760 4735);
DISPLAY 0.680851 (-1760 4735);
PAINT MONO (-1760 4735);
FORCEPROP 0 LASTPIN (-1750 4775) $PN 273
J 2
(-1760 4785);
DISPLAY 0.680851 (-1760 4785);
PAINT MONO (-1760 4785);
FORCEPROP 0 LASTPIN (-1750 4825) $PN 275
J 2
(-1760 4835);
DISPLAY 0.680851 (-1760 4835);
PAINT MONO (-1760 4835);
FORCEPROP 0 LASTPIN (-1750 4875) $PN 277
J 2
(-1760 4885);
DISPLAY 0.680851 (-1760 4885);
PAINT MONO (-1760 4885);
FORCEPROP 0 LASTPIN (-1750 4925) $PN 279
J 2
(-1760 4935);
DISPLAY 0.680851 (-1760 4935);
PAINT MONO (-1760 4935);
FORCEPROP 0 LASTPIN (-1750 4975) $PN 281
J 2
(-1760 4985);
DISPLAY 0.680851 (-1760 4985);
PAINT MONO (-1760 4985);
FORCEPROP 0 LASTPIN (-1750 5025) $PN 284
J 2
(-1760 5035);
DISPLAY 0.680851 (-1760 5035);
PAINT MONO (-1760 5035);
FORCEPROP 0 LASTPIN (-1750 5075) $PN 286
J 2
(-1760 5085);
DISPLAY 0.680851 (-1760 5085);
PAINT MONO (-1760 5085);
FORCEPROP 0 LASTPIN (-1750 5125) $PN 288
J 2
(-1760 5135);
DISPLAY 0.680851 (-1760 5135);
PAINT MONO (-1760 5135);
FORCEPROP 2 LAST PART_TYPE SMLF
J 0
(-1600 5700);
DISPLAY 1.021277 (-1600 5700);
FORCEPROP 1 LAST MATERIAL IO
J 0
(-1600 5450);
DISPLAY 0.468085 (-1600 5450);
PAINT SKYBLUE (-1600 5450);
FORCEPROP 2 LAST VALUE SCONN288_DDR506112002KQ
J 0
(-1600 5650);
DISPLAY 0.489362 (-1600 5650);
PAINT SKYBLUE (-1600 5650);
FORCEPROP 1 LAST CDS_LMAN_SYM_OUTLINE -450,1800,450,-1750
J 0
(-1150 3625);
DISPLAY 0.468085 (-1150 3625);
PAINT GREEN (-1150 3625);
DISPLAY INVISIBLE (-1150 3625);
FORCEPROP 1 LAST NEEDS_NO_SIZE TRUE
J 0
(-1150 3625);
DISPLAY 0.723404 (-1150 3625);
PAINT GREEN (-1150 3625);
DISPLAY INVISIBLE (-1150 3625);
FORCEPROP 2 LAST CDS_LIB pure_quanta
J 0
(-1150 3625);
DISPLAY INVISIBLE (-1150 3625);
FORCEPROP 1 LAST PATH I177
J 0
(-1150 3625);
DISPLAY 0.723404 (-1150 3625);
PAINT GREEN (-1150 3625);
DISPLAY INVISIBLE (-1150 3625);
FORCEPROP 1 LAST PART_NUMBER DFHST8FS479
J 0
(-1600 5525);
DISPLAY 0.468085 (-1600 5525);
PAINT SKYBLUE (-1600 5525);
DISPLAY INVISIBLE (-1600 5525);
FORCEADD OFFPAGE..1
(-8250 4475);
FORCEPROP 2 LAST $XR0 19 
J 0
(-8501 4475);
DISPLAY 0.638298 (-8501 4475);
PAINT MONO (-8501 4475);
FORCEPROP 2 LAST CDS_LIB mstr_standard
J 0
(-8250 4475);
DISPLAY 0.808511 (-8250 4475);
DISPLAY INVISIBLE (-8250 4475);
FORCEPROP 1 LAST OFFPAGE TRUE
J 0
(-7925 4350);
DISPLAY 0.872340 (-7925 4350);
PAINT GREEN (-7925 4350);
DISPLAY INVISIBLE (-7925 4350);
FORCEPROP 1 LAST COMMENT_BODY TRUE
J 0
(-8125 4375);
DISPLAY 0.872340 (-8125 4375);
PAINT GREEN (-8125 4375);
DISPLAY INVISIBLE (-8125 4375);
FORCEPROP 2 LAST PATH I18
J 0
(-8200 4550);
DISPLAY 1.021277 (-8200 4550);
DISPLAY INVISIBLE (-8200 4550);
FORCEADD Q_CAP..1
R 2
(-8550 3175);
FORCEPROP 1 LAST LOCATION C124
J 2
(-8600 3275);
DISPLAY 0.489362 (-8600 3275);
PAINT SKYBLUE (-8600 3275);
FORCEPROP 0 LAST $SEC 1
J 0
(-8600 3325);
DISPLAY 0.680851 (-8600 3325);
PAINT MONO (-8600 3325);
DISPLAY INVISIBLE (-8600 3325);
FORCEPROP 0 LAST CDS_SEC 1
J 0
(-8600 3325);
DISPLAY 1.021277 (-8600 3325);
DISPLAY INVISIBLE (-8600 3325);
FORCEPROP 1 LASTPIN (-8550 3275) $PN 1
J 2
(-8560 3255);
DISPLAY 0.489362 (-8560 3255);
PAINT MONO (-8560 3255);
FORCEPROP 1 LASTPIN (-8550 3075) $PN 2
J 2
(-8560 3055);
DISPLAY 0.489362 (-8560 3055);
PAINT MONO (-8560 3055);
FORCEPROP 1 LAST PACK_TYPE 0402
J 2
(-8600 2975);
DISPLAY 0.489362 (-8600 2975);
PAINT SKYBLUE (-8600 2975);
FORCEPROP 1 LAST VOLTAGE 25V
J 2
(-8600 3175);
DISPLAY 0.489362 (-8600 3175);
PAINT SKYBLUE (-8600 3175);
FORCEPROP 1 LAST VALUE 0.1UF
J 2
(-8600 3225);
DISPLAY 0.489362 (-8600 3225);
PAINT SKYBLUE (-8600 3225);
FORCEPROP 1 LAST TOLERANCE 10%
J 2
(-8600 3125);
DISPLAY 0.489362 (-8600 3125);
PAINT SKYBLUE (-8600 3125);
FORCEPROP 1 LAST MATERIAL X7R
J 2
(-8600 3075);
DISPLAY 0.489362 (-8600 3075);
PAINT SKYBLUE (-8600 3075);
FORCEPROP 2 LAST CDS_LIB pure_quanta
J 0
(-8550 3175);
DISPLAY INVISIBLE (-8550 3175);
FORCEPROP 0 LAST BOM_COST MEM
J 2
(-8605 3320);
DISPLAY 0.595745 (-8605 3320);
PAINT MONO (-8605 3320);
DISPLAY INVISIBLE (-8605 3320);
FORCEPROP 2 LAST ROOM 
J 2
(-8605 3320);
DISPLAY 0.595745 (-8605 3320);
PAINT RED (-8605 3320);
DISPLAY INVISIBLE (-8605 3320);
FORCEPROP 1 LAST PATH I185
J 2
(-8600 3325);
DISPLAY 0.978723 (-8600 3325);
PAINT WHITE (-8600 3325);
DISPLAY INVISIBLE (-8600 3325);
FORCEPROP 1 LAST PART_NUMBER CH4104K1B00
J 2
(-8600 3025);
DISPLAY 0.489362 (-8600 3025);
PAINT SKYBLUE (-8600 3025);
DISPLAY INVISIBLE (-8600 3025);
FORCEADD GND..1
(-8550 2950);
FORCEPROP 3 LASTPIN (-8550 3000) SIG_NAME GND\g
J 0
(-8540 3010);
DISPLAY 0.659574 (-8540 3010);
PAINT MONO (-8540 3010);
DISPLAY INVISIBLE (-8540 3010);
FORCEPROP 2 LAST BOM_COST MEM
J 0
(-8525 3075);
DISPLAY 0.659574 (-8525 3075);
DISPLAY INVISIBLE (-8525 3075);
FORCEPROP 1 LAST SIZE 1B
J 0
(-8475 2900);
DISPLAY 0.723404 (-8475 2900);
PAINT GREEN (-8475 2900);
DISPLAY INVISIBLE (-8475 2900);
FORCEPROP 2 LAST CDS_LIB mstr_symbols
J 0
(-8550 2950);
DISPLAY 0.808511 (-8550 2950);
DISPLAY INVISIBLE (-8550 2950);
FORCEPROP 1 LAST VOLTAGE 0
J 0
(-8570 3045);
DISPLAY 0.829787 (-8570 3045);
PAINT SKYBLUE (-8570 3045);
DISPLAY INVISIBLE (-8570 3045);
FORCEPROP 2 LAST ROOM MEM_EFGH_DECOUPLING_CAPS
J 0
(-8525 3025);
DISPLAY 0.659574 (-8525 3025);
PAINT RED (-8525 3025);
DISPLAY INVISIBLE (-8525 3025);
FORCEPROP 1 LAST BODY_TYPE PLUMBING
J 0
(-8595 2907);
DISPLAY 0.276596 (-8595 2907);
PAINT GREEN (-8595 2907);
DISPLAY INVISIBLE (-8595 2907);
FORCEPROP 1 LAST HDL_POWER GND
J 0
(-8550 3100);
DISPLAY 0.723404 (-8550 3100);
PAINT GREEN (-8550 3100);
DISPLAY INVISIBLE (-8550 3100);
FORCEPROP 1 LAST PATH I186
J 0
(-8475 2950);
DISPLAY 0.872340 (-8475 2950);
PAINT AQUA (-8475 2950);
DISPLAY INVISIBLE (-8475 2950);
FORCEADD OFFPAGE..6
(-9000 2075);
FORCEPROP 2 LAST $XR4 97 
J 0
(-9339 2039);
DISPLAY 0.638298 (-9339 2039);
PAINT MONO (-9339 2039);
FORCEPROP 2 LAST $XR3 96 
J 0
(-9249 2039);
DISPLAY 0.638298 (-9249 2039);
PAINT MONO (-9249 2039);
FORCEPROP 2 LAST $XR2 94 
J 0
(-9429 2075);
DISPLAY 0.638298 (-9429 2075);
PAINT MONO (-9429 2075);
FORCEPROP 2 LAST $XR1 93 
J 0
(-9339 2075);
DISPLAY 0.638298 (-9339 2075);
PAINT MONO (-9339 2075);
FORCEPROP 2 LAST $XR0 92 
J 0
(-9249 2075);
DISPLAY 0.638298 (-9249 2075);
PAINT MONO (-9249 2075);
FORCEPROP 2 LAST CDS_LIB mstr_standard
J 0
(-9000 2075);
DISPLAY INVISIBLE (-9000 2075);
FORCEPROP 1 LAST OFFPAGE TRUE
J 0
(-8675 1950);
DISPLAY 0.872340 (-8675 1950);
PAINT GREEN (-8675 1950);
DISPLAY INVISIBLE (-8675 1950);
FORCEPROP 1 LAST COMMENT_BODY TRUE
J 0
(-8900 2000);
DISPLAY 0.872340 (-8900 2000);
PAINT GREEN (-8900 2000);
DISPLAY INVISIBLE (-8900 2000);
FORCEPROP 2 LAST PATH I187
J 0
(-8950 2150);
DISPLAY 1.021277 (-8950 2150);
DISPLAY INVISIBLE (-8950 2150);
FORCEADD Q_RES..1
R 2
(-8450 2075);
FORCEPROP 1 LAST LOCATION R300
J 2
(-8400 2125);
DISPLAY 0.489362 (-8400 2125);
PAINT SKYBLUE (-8400 2125);
FORCEPROP 0 LAST $SEC 1
J 0
(-8400 2175);
DISPLAY 0.680851 (-8400 2175);
PAINT MONO (-8400 2175);
DISPLAY INVISIBLE (-8400 2175);
FORCEPROP 0 LAST CDS_SEC 1
J 0
(-8400 2175);
DISPLAY 1.021277 (-8400 2175);
DISPLAY INVISIBLE (-8400 2175);
FORCEPROP 1 LASTPIN (-8350 2075) $PN 1
J 2
(-8362 2087);
DISPLAY 0.489362 (-8362 2087);
PAINT MONO (-8362 2087);
FORCEPROP 1 LASTPIN (-8550 2075) $PN 2
J 2
(-8512 2087);
DISPLAY 0.489362 (-8512 2087);
PAINT MONO (-8512 2087);
FORCEPROP 1 LAST VALUE 1K
J 0
(-8450 2025);
DISPLAY 0.489362 (-8450 2025);
PAINT SKYBLUE (-8450 2025);
FORCEPROP 1 LAST TOLERANCE 1%
J 2
(-8325 2050);
DISPLAY 0.489362 (-8325 2050);
PAINT SKYBLUE (-8325 2050);
DISPLAY INVISIBLE (-8325 2050);
FORCEPROP 2 LAST CDS_LIB pure_quanta
J 0
(-8450 2075);
DISPLAY INVISIBLE (-8450 2075);
FORCEPROP 2 LAST BOM_COST MEM
J 0
(-8475 2225);
DISPLAY 0.744681 (-8475 2225);
PAINT WHITE (-8475 2225);
DISPLAY INVISIBLE (-8475 2225);
FORCEPROP 1 LAST WATTAGE 1/16W
J 0
(-8375 2000);
DISPLAY 0.489362 (-8375 2000);
PAINT SKYBLUE (-8375 2000);
DISPLAY INVISIBLE (-8375 2000);
FORCEPROP 1 LAST MATERIAL CHIP
J 0
(-8625 2050);
DISPLAY 0.489362 (-8625 2050);
PAINT SKYBLUE (-8625 2050);
DISPLAY INVISIBLE (-8625 2050);
FORCEPROP 1 LAST PACK_TYPE 0402LF
J 0
(-8625 2000);
DISPLAY 0.489362 (-8625 2000);
PAINT SKYBLUE (-8625 2000);
DISPLAY INVISIBLE (-8625 2000);
FORCEPROP 2 LAST ROOM 
J 0
(-8475 2175);
DISPLAY 0.744681 (-8475 2175);
PAINT RED (-8475 2175);
DISPLAY INVISIBLE (-8475 2175);
FORCEPROP 1 LAST PATH I188
J 2
(-8400 2225);
DISPLAY 0.978723 (-8400 2225);
PAINT WHITE (-8400 2225);
DISPLAY INVISIBLE (-8400 2225);
FORCEPROP 1 LAST PART_NUMBER CS21002FB06
J 0
(-8550 2125);
DISPLAY 0.489362 (-8550 2125);
PAINT SKYBLUE (-8550 2125);
DISPLAY INVISIBLE (-8550 2125);
FORCEADD Q_RES..2
(-8325 2225);
FORCEPROP 1 LAST LOCATION R99
J 0
(-8280 2350);
DISPLAY 0.489362 (-8280 2350);
PAINT SKYBLUE (-8280 2350);
FORCEPROP 0 LAST $SEC 1
J 0
(-8275 2400);
DISPLAY 0.680851 (-8275 2400);
PAINT MONO (-8275 2400);
DISPLAY INVISIBLE (-8275 2400);
FORCEPROP 0 LAST CDS_SEC 1
J 0
(-8275 2400);
DISPLAY 1.021277 (-8275 2400);
DISPLAY INVISIBLE (-8275 2400);
FORCEPROP 1 LASTPIN (-8325 2325) $PN 1
J 0
(-8320 2287);
DISPLAY 0.489362 (-8320 2287);
PAINT MONO (-8320 2287);
FORCEPROP 1 LASTPIN (-8325 2125) $PN 2
J 0
(-8320 2135);
DISPLAY 0.489362 (-8320 2135);
PAINT MONO (-8320 2135);
FORCEPROP 1 LAST TOLERANCE 1%
J 0
(-8275 2275);
DISPLAY 0.489362 (-8275 2275);
PAINT SKYBLUE (-8275 2275);
FORCEPROP 1 LAST WATTAGE 1/16W
J 0
(-8275 2250);
DISPLAY 0.489362 (-8275 2250);
PAINT SKYBLUE (-8275 2250);
FORCEPROP 1 LAST MATERIAL EMPTY
J 0
(-8275 2225);
DISPLAY 0.489362 (-8275 2225);
PAINT RED (-8275 2225);
FORCEPROP 1 LAST VALUE 1K
J 0
(-8280 2300);
DISPLAY 0.489362 (-8280 2300);
PAINT SKYBLUE (-8280 2300);
FORCEPROP 1 LAST PACK_TYPE 0402LF
J 0
(-8275 2175);
DISPLAY 0.489362 (-8275 2175);
PAINT SKYBLUE (-8275 2175);
FORCEPROP 2 LAST CDS_LIB pure_quanta
J 0
(-8325 2225);
DISPLAY INVISIBLE (-8325 2225);
FORCEPROP 2 LAST BOM_COST MEM
J 0
(-8275 2400);
DISPLAY 0.808511 (-8275 2400);
DISPLAY INVISIBLE (-8275 2400);
FORCEPROP 2 LAST ROOM 
J 0
(-8275 2450);
DISPLAY 0.808511 (-8275 2450);
PAINT RED (-8275 2450);
DISPLAY INVISIBLE (-8275 2450);
FORCEPROP 1 LAST PATH I189
J 0
(-8275 2400);
DISPLAY 0.978723 (-8275 2400);
PAINT WHITE (-8275 2400);
DISPLAY INVISIBLE (-8275 2400);
FORCEPROP 1 LAST PART_NUMBER CS21002FB06
J 0
(-8275 2200);
DISPLAY 0.489362 (-8275 2200);
PAINT SKYBLUE (-8275 2200);
DISPLAY INVISIBLE (-8275 2200);
FORCEADD OFFPAGE..1
(-8250 4325);
FORCEPROP 2 LAST $XR0 19 
J 0
(-8501 4325);
DISPLAY 0.638298 (-8501 4325);
PAINT MONO (-8501 4325);
FORCEPROP 2 LAST CDS_LIB mstr_standard
J 0
(-8250 4325);
DISPLAY 0.808511 (-8250 4325);
DISPLAY INVISIBLE (-8250 4325);
FORCEPROP 1 LAST OFFPAGE TRUE
J 0
(-7925 4200);
DISPLAY 0.872340 (-7925 4200);
PAINT GREEN (-7925 4200);
DISPLAY INVISIBLE (-7925 4200);
FORCEPROP 1 LAST COMMENT_BODY TRUE
J 0
(-8125 4225);
DISPLAY 0.872340 (-8125 4225);
PAINT GREEN (-8125 4225);
DISPLAY INVISIBLE (-8125 4225);
FORCEPROP 2 LAST PATH I19
J 0
(-8200 4400);
DISPLAY 1.021277 (-8200 4400);
DISPLAY INVISIBLE (-8200 4400);
FORCEADD VCC_CORE..1
(-8325 2400);
FORCEPROP 3 LASTPIN (-8325 2350) SIG_NAME P3V3\g
J 0
(-8315 2360);
DISPLAY 0.659574 (-8315 2360);
PAINT MONO (-8315 2360);
DISPLAY INVISIBLE (-8315 2360);
FORCEPROP 1 LAST HDL_POWER P3V3
J 1
(-8325 2450);
DISPLAY 0.489362 (-8325 2450);
PAINT GREEN (-8325 2450);
FORCEPROP 2 LAST CDS_LIB mstr_symbols
J 0
(-8325 2400);
DISPLAY INVISIBLE (-8325 2400);
FORCEPROP 0 LAST VOLTAGE 3.3
J 0
(-8600 2550);
DISPLAY 1.021277 (-8600 2550);
PAINT SKYBLUE (-8600 2550);
DISPLAY INVISIBLE (-8600 2550);
FORCEPROP 2 LAST ROOM PVCCINFAON_CPU0_CTRL
J 0
(-8325 2500);
DISPLAY 0.808511 (-8325 2500);
PAINT RED (-8325 2500);
DISPLAY INVISIBLE (-8325 2500);
FORCEPROP 1 LAST PATH I190
J 0
(-8275 2425);
DISPLAY 0.872340 (-8275 2425);
PAINT AQUA (-8275 2425);
DISPLAY INVISIBLE (-8275 2425);
FORCEADD OFFPAGE..2
(-2375 4275);
FORCEPROP 2 LAST $XR0 19 
J 0
(-2186 4275);
DISPLAY 0.638298 (-2186 4275);
PAINT MONO (-2186 4275);
FORCEPROP 2 LAST CDS_LIB mstr_standard
J 0
(-2375 4275);
DISPLAY 0.723404 (-2375 4275);
PAINT MONO (-2375 4275);
DISPLAY INVISIBLE (-2375 4275);
FORCEPROP 1 LAST OFFPAGE TRUE
J 0
(-2050 4150);
DISPLAY 0.723404 (-2050 4150);
PAINT GREEN (-2050 4150);
DISPLAY INVISIBLE (-2050 4150);
FORCEPROP 1 LAST COMMENT_BODY TRUE
J 0
(-2420 4180);
DISPLAY 0.872340 (-2420 4180);
PAINT GREEN (-2420 4180);
DISPLAY INVISIBLE (-2420 4180);
FORCEPROP 2 LAST PATH I192
J 0
(-2175 4325);
DISPLAY 0.680851 (-2175 4325);
DISPLAY INVISIBLE (-2175 4325);
FORCEADD OFFPAGE..2
(-2375 4225);
FORCEPROP 2 LAST $XR0 19 
J 0
(-2186 4225);
DISPLAY 0.638298 (-2186 4225);
PAINT MONO (-2186 4225);
FORCEPROP 2 LAST CDS_LIB mstr_standard
J 0
(-2375 4225);
DISPLAY 0.723404 (-2375 4225);
PAINT MONO (-2375 4225);
DISPLAY INVISIBLE (-2375 4225);
FORCEPROP 1 LAST OFFPAGE TRUE
J 0
(-2050 4100);
DISPLAY 0.723404 (-2050 4100);
PAINT GREEN (-2050 4100);
DISPLAY INVISIBLE (-2050 4100);
FORCEPROP 1 LAST COMMENT_BODY TRUE
J 0
(-2420 4130);
DISPLAY 0.872340 (-2420 4130);
PAINT GREEN (-2420 4130);
DISPLAY INVISIBLE (-2420 4130);
FORCEPROP 2 LAST PATH I193
J 0
(-2175 4275);
DISPLAY 0.680851 (-2175 4275);
DISPLAY INVISIBLE (-2175 4275);
FORCEADD OFFPAGE..2
(-2375 3175);
FORCEPROP 2 LAST $XR0 19 
J 0
(-2186 3175);
DISPLAY 0.638298 (-2186 3175);
PAINT MONO (-2186 3175);
FORCEPROP 2 LAST CDS_LIB mstr_standard
J 0
(-2375 3175);
DISPLAY 0.723404 (-2375 3175);
PAINT MONO (-2375 3175);
DISPLAY INVISIBLE (-2375 3175);
FORCEPROP 1 LAST OFFPAGE TRUE
J 0
(-2050 3050);
DISPLAY 0.723404 (-2050 3050);
PAINT GREEN (-2050 3050);
DISPLAY INVISIBLE (-2050 3050);
FORCEPROP 1 LAST COMMENT_BODY TRUE
J 0
(-2420 3080);
DISPLAY 0.872340 (-2420 3080);
PAINT GREEN (-2420 3080);
DISPLAY INVISIBLE (-2420 3080);
FORCEPROP 2 LAST PATH I194
J 0
(-2175 3225);
DISPLAY 0.680851 (-2175 3225);
DISPLAY INVISIBLE (-2175 3225);
FORCEADD OFFPAGE..2
(-2375 3225);
FORCEPROP 2 LAST $XR0 19 
J 0
(-2186 3225);
DISPLAY 0.638298 (-2186 3225);
PAINT MONO (-2186 3225);
FORCEPROP 2 LAST CDS_LIB mstr_standard
J 0
(-2375 3225);
DISPLAY 0.723404 (-2375 3225);
PAINT MONO (-2375 3225);
DISPLAY INVISIBLE (-2375 3225);
FORCEPROP 1 LAST OFFPAGE TRUE
J 0
(-2050 3100);
DISPLAY 0.723404 (-2050 3100);
PAINT GREEN (-2050 3100);
DISPLAY INVISIBLE (-2050 3100);
FORCEPROP 1 LAST COMMENT_BODY TRUE
J 0
(-2420 3130);
DISPLAY 0.872340 (-2420 3130);
PAINT GREEN (-2420 3130);
DISPLAY INVISIBLE (-2420 3130);
FORCEPROP 2 LAST PATH I195
J 0
(-2175 3275);
DISPLAY 0.680851 (-2175 3275);
DISPLAY INVISIBLE (-2175 3275);
FORCEADD TAP..1
(-3175 4075);
FORCEPROP 3 LASTPIN (-3225 4075) SIG_NAME M_J_CPU0_SA_DQS_DN<8>
J 0
(-3215 4085);
DISPLAY 0.659574 (-3215 4085);
PAINT MONO (-3215 4085);
DISPLAY INVISIBLE (-3215 4085);
FORCEPROP 1 LASTPIN (-3225 4075) BN 8
J 0
(-3237 4083);
DISPLAY 0.489362 (-3237 4083);
PAINT GREEN (-3237 4083);
FORCEPROP 2 LAST CDS_LIB mstr_standard
J 0
(-3175 4075);
DISPLAY 0.723404 (-3175 4075);
PAINT MONO (-3175 4075);
DISPLAY INVISIBLE (-3175 4075);
FORCEPROP 1 LAST BODY_TYPE PLUMBING
J 0
(-3175 4125);
DISPLAY 0.872340 (-3175 4125);
PAINT GREEN (-3175 4125);
DISPLAY INVISIBLE (-3175 4125);
FORCEPROP 1 LAST HDL_TAP TRUE
J 0
(-2850 3950);
DISPLAY 0.872340 (-2850 3950);
DISPLAY INVISIBLE (-2850 3950);
FORCEPROP 1 LAST PATH I196
J 0
(-3177 4075);
DISPLAY 0.872340 (-3177 4075);
PAINT GREEN (-3177 4075);
DISPLAY INVISIBLE (-3177 4075);
FORCEADD TAP..1
(-3175 4175);
FORCEPROP 3 LASTPIN (-3225 4175) SIG_NAME M_J_CPU0_SA_DQS_DN<9>
J 0
(-3215 4185);
DISPLAY 0.659574 (-3215 4185);
PAINT MONO (-3215 4185);
DISPLAY INVISIBLE (-3215 4185);
FORCEPROP 1 LASTPIN (-3225 4175) BN 9
J 0
(-3237 4183);
DISPLAY 0.489362 (-3237 4183);
PAINT GREEN (-3237 4183);
FORCEPROP 2 LAST CDS_LIB mstr_standard
J 0
(-3175 4175);
DISPLAY 0.723404 (-3175 4175);
PAINT MONO (-3175 4175);
DISPLAY INVISIBLE (-3175 4175);
FORCEPROP 1 LAST BODY_TYPE PLUMBING
J 0
(-3175 4225);
DISPLAY 0.872340 (-3175 4225);
PAINT GREEN (-3175 4225);
DISPLAY INVISIBLE (-3175 4225);
FORCEPROP 1 LAST HDL_TAP TRUE
J 0
(-2850 4050);
DISPLAY 0.872340 (-2850 4050);
DISPLAY INVISIBLE (-2850 4050);
FORCEPROP 1 LAST PATH I197
J 0
(-3177 4175);
DISPLAY 0.872340 (-3177 4175);
PAINT GREEN (-3177 4175);
DISPLAY INVISIBLE (-3177 4175);
FORCEADD TAP..1
(-3375 4225);
FORCEPROP 3 LASTPIN (-3425 4225) SIG_NAME M_J_CPU0_SA_DQS_DP<9>
J 0
(-3415 4235);
DISPLAY 0.659574 (-3415 4235);
PAINT MONO (-3415 4235);
DISPLAY INVISIBLE (-3415 4235);
FORCEPROP 1 LASTPIN (-3425 4225) BN 9
J 0
(-3437 4233);
DISPLAY 0.489362 (-3437 4233);
PAINT GREEN (-3437 4233);
FORCEPROP 2 LAST CDS_LIB mstr_standard
J 0
(-3375 4225);
DISPLAY 0.723404 (-3375 4225);
PAINT MONO (-3375 4225);
DISPLAY INVISIBLE (-3375 4225);
FORCEPROP 1 LAST BODY_TYPE PLUMBING
J 0
(-3375 4275);
DISPLAY 0.872340 (-3375 4275);
PAINT GREEN (-3375 4275);
DISPLAY INVISIBLE (-3375 4275);
FORCEPROP 1 LAST HDL_TAP TRUE
J 0
(-3050 4100);
DISPLAY 0.872340 (-3050 4100);
DISPLAY INVISIBLE (-3050 4100);
FORCEPROP 1 LAST PATH I198
J 0
(-3377 4225);
DISPLAY 0.872340 (-3377 4225);
PAINT GREEN (-3377 4225);
DISPLAY INVISIBLE (-3377 4225);
FORCEADD TAP..1
(-3375 4125);
FORCEPROP 3 LASTPIN (-3425 4125) SIG_NAME M_J_CPU0_SA_DQS_DP<8>
J 0
(-3415 4135);
DISPLAY 0.659574 (-3415 4135);
PAINT MONO (-3415 4135);
DISPLAY INVISIBLE (-3415 4135);
FORCEPROP 1 LASTPIN (-3425 4125) BN 8
J 0
(-3437 4133);
DISPLAY 0.489362 (-3437 4133);
PAINT GREEN (-3437 4133);
FORCEPROP 2 LAST CDS_LIB mstr_standard
J 0
(-3375 4125);
DISPLAY 0.723404 (-3375 4125);
PAINT MONO (-3375 4125);
DISPLAY INVISIBLE (-3375 4125);
FORCEPROP 1 LAST BODY_TYPE PLUMBING
J 0
(-3375 4175);
DISPLAY 0.872340 (-3375 4175);
PAINT GREEN (-3375 4175);
DISPLAY INVISIBLE (-3375 4175);
FORCEPROP 1 LAST HDL_TAP TRUE
J 0
(-3050 4000);
DISPLAY 0.872340 (-3050 4000);
DISPLAY INVISIBLE (-3050 4000);
FORCEPROP 1 LAST PATH I199
J 0
(-3377 4125);
DISPLAY 0.872340 (-3377 4125);
PAINT GREEN (-3377 4125);
DISPLAY INVISIBLE (-3377 4125);
FORCEADD OFFPAGE..5
(-8250 1925);
FORCEPROP 2 LAST $XR0 19 
J 0
(-8474 1925);
DISPLAY 0.638298 (-8474 1925);
PAINT MONO (-8474 1925);
FORCEPROP 2 LAST CDS_LIB mstr_standard
J 0
(-8250 1925);
DISPLAY 0.808511 (-8250 1925);
DISPLAY INVISIBLE (-8250 1925);
FORCEPROP 1 LAST OFFPAGE TRUE
J 0
(-7925 1800);
DISPLAY 0.872340 (-7925 1800);
PAINT GREEN (-7925 1800);
DISPLAY INVISIBLE (-7925 1800);
FORCEPROP 1 LAST COMMENT_BODY TRUE
J 0
(-8150 1850);
DISPLAY 0.872340 (-8150 1850);
PAINT GREEN (-8150 1850);
DISPLAY INVISIBLE (-8150 1850);
FORCEPROP 2 LAST PATH I2
J 0
(-8200 2000);
DISPLAY 1.021277 (-8200 2000);
DISPLAY INVISIBLE (-8200 2000);
FORCEADD OFFPAGE..1
(-8250 5375);
FORCEPROP 2 LAST $XR0 19 
J 0
(-8501 5375);
DISPLAY 0.638298 (-8501 5375);
PAINT MONO (-8501 5375);
FORCEPROP 2 LAST CDS_LIB mstr_standard
J 0
(-8250 5375);
DISPLAY 0.723404 (-8250 5375);
PAINT MONO (-8250 5375);
DISPLAY INVISIBLE (-8250 5375);
FORCEPROP 1 LAST OFFPAGE TRUE
J 0
(-7925 5250);
DISPLAY 0.872340 (-7925 5250);
PAINT GREEN (-7925 5250);
DISPLAY INVISIBLE (-7925 5250);
FORCEPROP 1 LAST COMMENT_BODY TRUE
J 0
(-8125 5275);
DISPLAY 0.872340 (-8125 5275);
PAINT GREEN (-8125 5275);
DISPLAY INVISIBLE (-8125 5275);
FORCEPROP 2 LAST PATH I20
J 0
(-8200 5450);
DISPLAY 1.021277 (-8200 5450);
DISPLAY INVISIBLE (-8200 5450);
FORCEADD TAP..1
(-3175 3975);
FORCEPROP 3 LASTPIN (-3225 3975) SIG_NAME M_J_CPU0_SA_DQS_DN<7>
J 0
(-3215 3985);
DISPLAY 0.659574 (-3215 3985);
PAINT MONO (-3215 3985);
DISPLAY INVISIBLE (-3215 3985);
FORCEPROP 1 LASTPIN (-3225 3975) BN 7
J 0
(-3237 3983);
DISPLAY 0.489362 (-3237 3983);
PAINT GREEN (-3237 3983);
FORCEPROP 2 LAST CDS_LIB mstr_standard
J 0
(-3175 3975);
DISPLAY 0.723404 (-3175 3975);
PAINT MONO (-3175 3975);
DISPLAY INVISIBLE (-3175 3975);
FORCEPROP 1 LAST BODY_TYPE PLUMBING
J 0
(-3175 4025);
DISPLAY 0.872340 (-3175 4025);
PAINT GREEN (-3175 4025);
DISPLAY INVISIBLE (-3175 4025);
FORCEPROP 1 LAST HDL_TAP TRUE
J 0
(-2850 3850);
DISPLAY 0.872340 (-2850 3850);
DISPLAY INVISIBLE (-2850 3850);
FORCEPROP 1 LAST PATH I200
J 0
(-3177 3975);
DISPLAY 0.872340 (-3177 3975);
PAINT GREEN (-3177 3975);
DISPLAY INVISIBLE (-3177 3975);
FORCEADD TAP..1
(-3175 3875);
FORCEPROP 3 LASTPIN (-3225 3875) SIG_NAME M_J_CPU0_SA_DQS_DN<6>
J 0
(-3215 3885);
DISPLAY 0.659574 (-3215 3885);
PAINT MONO (-3215 3885);
DISPLAY INVISIBLE (-3215 3885);
FORCEPROP 1 LASTPIN (-3225 3875) BN 6
J 0
(-3237 3883);
DISPLAY 0.489362 (-3237 3883);
PAINT GREEN (-3237 3883);
FORCEPROP 2 LAST CDS_LIB mstr_standard
J 0
(-3175 3875);
DISPLAY 0.723404 (-3175 3875);
PAINT MONO (-3175 3875);
DISPLAY INVISIBLE (-3175 3875);
FORCEPROP 1 LAST BODY_TYPE PLUMBING
J 0
(-3175 3925);
DISPLAY 0.872340 (-3175 3925);
PAINT GREEN (-3175 3925);
DISPLAY INVISIBLE (-3175 3925);
FORCEPROP 1 LAST HDL_TAP TRUE
J 0
(-2850 3750);
DISPLAY 0.872340 (-2850 3750);
DISPLAY INVISIBLE (-2850 3750);
FORCEPROP 1 LAST PATH I201
J 0
(-3177 3875);
DISPLAY 0.872340 (-3177 3875);
PAINT GREEN (-3177 3875);
DISPLAY INVISIBLE (-3177 3875);
FORCEADD TAP..1
(-3175 3775);
FORCEPROP 3 LASTPIN (-3225 3775) SIG_NAME M_J_CPU0_SA_DQS_DN<5>
J 0
(-3215 3785);
DISPLAY 0.659574 (-3215 3785);
PAINT MONO (-3215 3785);
DISPLAY INVISIBLE (-3215 3785);
FORCEPROP 1 LASTPIN (-3225 3775) BN 5
J 0
(-3237 3783);
DISPLAY 0.489362 (-3237 3783);
PAINT GREEN (-3237 3783);
FORCEPROP 2 LAST CDS_LIB mstr_standard
J 0
(-3175 3775);
DISPLAY 0.723404 (-3175 3775);
PAINT MONO (-3175 3775);
DISPLAY INVISIBLE (-3175 3775);
FORCEPROP 1 LAST BODY_TYPE PLUMBING
J 0
(-3175 3825);
DISPLAY 0.872340 (-3175 3825);
PAINT GREEN (-3175 3825);
DISPLAY INVISIBLE (-3175 3825);
FORCEPROP 1 LAST HDL_TAP TRUE
J 0
(-2850 3650);
DISPLAY 0.872340 (-2850 3650);
DISPLAY INVISIBLE (-2850 3650);
FORCEPROP 1 LAST PATH I202
J 0
(-3177 3775);
DISPLAY 0.872340 (-3177 3775);
PAINT GREEN (-3177 3775);
DISPLAY INVISIBLE (-3177 3775);
FORCEADD TAP..1
(-3175 3675);
FORCEPROP 3 LASTPIN (-3225 3675) SIG_NAME M_J_CPU0_SA_DQS_DN<4>
J 0
(-3215 3685);
DISPLAY 0.659574 (-3215 3685);
PAINT MONO (-3215 3685);
DISPLAY INVISIBLE (-3215 3685);
FORCEPROP 1 LASTPIN (-3225 3675) BN 4
J 0
(-3237 3683);
DISPLAY 0.489362 (-3237 3683);
PAINT GREEN (-3237 3683);
FORCEPROP 2 LAST CDS_LIB mstr_standard
J 0
(-3175 3675);
DISPLAY 0.723404 (-3175 3675);
PAINT MONO (-3175 3675);
DISPLAY INVISIBLE (-3175 3675);
FORCEPROP 1 LAST BODY_TYPE PLUMBING
J 0
(-3175 3725);
DISPLAY 0.872340 (-3175 3725);
PAINT GREEN (-3175 3725);
DISPLAY INVISIBLE (-3175 3725);
FORCEPROP 1 LAST HDL_TAP TRUE
J 0
(-2850 3550);
DISPLAY 0.872340 (-2850 3550);
DISPLAY INVISIBLE (-2850 3550);
FORCEPROP 1 LAST PATH I203
J 0
(-3177 3675);
DISPLAY 0.872340 (-3177 3675);
PAINT GREEN (-3177 3675);
DISPLAY INVISIBLE (-3177 3675);
FORCEADD TAP..1
(-3175 3575);
FORCEPROP 3 LASTPIN (-3225 3575) SIG_NAME M_J_CPU0_SA_DQS_DN<3>
J 0
(-3215 3585);
DISPLAY 0.659574 (-3215 3585);
PAINT MONO (-3215 3585);
DISPLAY INVISIBLE (-3215 3585);
FORCEPROP 1 LASTPIN (-3225 3575) BN 3
J 0
(-3237 3583);
DISPLAY 0.489362 (-3237 3583);
PAINT GREEN (-3237 3583);
FORCEPROP 2 LAST CDS_LIB mstr_standard
J 0
(-3175 3575);
DISPLAY 0.723404 (-3175 3575);
PAINT MONO (-3175 3575);
DISPLAY INVISIBLE (-3175 3575);
FORCEPROP 1 LAST BODY_TYPE PLUMBING
J 0
(-3175 3625);
DISPLAY 0.872340 (-3175 3625);
PAINT GREEN (-3175 3625);
DISPLAY INVISIBLE (-3175 3625);
FORCEPROP 1 LAST HDL_TAP TRUE
J 0
(-2850 3450);
DISPLAY 0.872340 (-2850 3450);
DISPLAY INVISIBLE (-2850 3450);
FORCEPROP 1 LAST PATH I204
J 0
(-3177 3575);
DISPLAY 0.872340 (-3177 3575);
PAINT GREEN (-3177 3575);
DISPLAY INVISIBLE (-3177 3575);
FORCEADD TAP..1
(-3175 3475);
FORCEPROP 3 LASTPIN (-3225 3475) SIG_NAME M_J_CPU0_SA_DQS_DN<2>
J 0
(-3215 3485);
DISPLAY 0.659574 (-3215 3485);
PAINT MONO (-3215 3485);
DISPLAY INVISIBLE (-3215 3485);
FORCEPROP 1 LASTPIN (-3225 3475) BN 2
J 0
(-3237 3483);
DISPLAY 0.489362 (-3237 3483);
PAINT GREEN (-3237 3483);
FORCEPROP 2 LAST CDS_LIB mstr_standard
J 0
(-3175 3475);
DISPLAY 0.723404 (-3175 3475);
PAINT MONO (-3175 3475);
DISPLAY INVISIBLE (-3175 3475);
FORCEPROP 1 LAST BODY_TYPE PLUMBING
J 0
(-3175 3525);
DISPLAY 0.872340 (-3175 3525);
PAINT GREEN (-3175 3525);
DISPLAY INVISIBLE (-3175 3525);
FORCEPROP 1 LAST HDL_TAP TRUE
J 0
(-2850 3350);
DISPLAY 0.872340 (-2850 3350);
DISPLAY INVISIBLE (-2850 3350);
FORCEPROP 1 LAST PATH I205
J 0
(-3177 3475);
DISPLAY 0.872340 (-3177 3475);
PAINT GREEN (-3177 3475);
DISPLAY INVISIBLE (-3177 3475);
FORCEADD TAP..1
(-3175 3375);
FORCEPROP 3 LASTPIN (-3225 3375) SIG_NAME M_J_CPU0_SA_DQS_DN<1>
J 0
(-3215 3385);
DISPLAY 0.659574 (-3215 3385);
PAINT MONO (-3215 3385);
DISPLAY INVISIBLE (-3215 3385);
FORCEPROP 1 LASTPIN (-3225 3375) BN 1
J 0
(-3237 3383);
DISPLAY 0.489362 (-3237 3383);
PAINT GREEN (-3237 3383);
FORCEPROP 2 LAST CDS_LIB mstr_standard
J 0
(-3175 3375);
DISPLAY 0.723404 (-3175 3375);
PAINT MONO (-3175 3375);
DISPLAY INVISIBLE (-3175 3375);
FORCEPROP 1 LAST BODY_TYPE PLUMBING
J 0
(-3175 3425);
DISPLAY 0.872340 (-3175 3425);
PAINT GREEN (-3175 3425);
DISPLAY INVISIBLE (-3175 3425);
FORCEPROP 1 LAST HDL_TAP TRUE
J 0
(-2850 3250);
DISPLAY 0.872340 (-2850 3250);
DISPLAY INVISIBLE (-2850 3250);
FORCEPROP 1 LAST PATH I206
J 0
(-3177 3375);
DISPLAY 0.872340 (-3177 3375);
PAINT GREEN (-3177 3375);
DISPLAY INVISIBLE (-3177 3375);
FORCEADD TAP..1
(-3175 3275);
FORCEPROP 3 LASTPIN (-3225 3275) SIG_NAME M_J_CPU0_SA_DQS_DN<0>
J 0
(-3215 3285);
DISPLAY 0.659574 (-3215 3285);
PAINT MONO (-3215 3285);
DISPLAY INVISIBLE (-3215 3285);
FORCEPROP 1 LASTPIN (-3225 3275) BN 0
J 0
(-3237 3283);
DISPLAY 0.489362 (-3237 3283);
PAINT GREEN (-3237 3283);
FORCEPROP 2 LAST CDS_LIB mstr_standard
J 0
(-3175 3275);
DISPLAY 0.723404 (-3175 3275);
PAINT MONO (-3175 3275);
DISPLAY INVISIBLE (-3175 3275);
FORCEPROP 1 LAST BODY_TYPE PLUMBING
J 0
(-3175 3325);
DISPLAY 0.872340 (-3175 3325);
PAINT GREEN (-3175 3325);
DISPLAY INVISIBLE (-3175 3325);
FORCEPROP 1 LAST HDL_TAP TRUE
J 0
(-2850 3150);
DISPLAY 0.872340 (-2850 3150);
DISPLAY INVISIBLE (-2850 3150);
FORCEPROP 1 LAST PATH I207
J 0
(-3177 3275);
DISPLAY 0.872340 (-3177 3275);
PAINT GREEN (-3177 3275);
DISPLAY INVISIBLE (-3177 3275);
FORCEADD TAP..1
(-3175 3125);
FORCEPROP 3 LASTPIN (-3225 3125) SIG_NAME M_J_CPU0_SB_DQS_DN<9>
J 0
(-3215 3135);
DISPLAY 0.659574 (-3215 3135);
PAINT MONO (-3215 3135);
DISPLAY INVISIBLE (-3215 3135);
FORCEPROP 1 LASTPIN (-3225 3125) BN 9
J 0
(-3237 3133);
DISPLAY 0.489362 (-3237 3133);
PAINT GREEN (-3237 3133);
FORCEPROP 2 LAST CDS_LIB mstr_standard
J 0
(-3175 3125);
DISPLAY 0.723404 (-3175 3125);
PAINT MONO (-3175 3125);
DISPLAY INVISIBLE (-3175 3125);
FORCEPROP 1 LAST BODY_TYPE PLUMBING
J 0
(-3175 3175);
DISPLAY 0.872340 (-3175 3175);
PAINT GREEN (-3175 3175);
DISPLAY INVISIBLE (-3175 3175);
FORCEPROP 1 LAST HDL_TAP TRUE
J 0
(-2850 3000);
DISPLAY 0.872340 (-2850 3000);
DISPLAY INVISIBLE (-2850 3000);
FORCEPROP 1 LAST PATH I208
J 0
(-3177 3125);
DISPLAY 0.872340 (-3177 3125);
PAINT GREEN (-3177 3125);
DISPLAY INVISIBLE (-3177 3125);
FORCEADD TAP..1
(-3375 4025);
FORCEPROP 3 LASTPIN (-3425 4025) SIG_NAME M_J_CPU0_SA_DQS_DP<7>
J 0
(-3415 4035);
DISPLAY 0.659574 (-3415 4035);
PAINT MONO (-3415 4035);
DISPLAY INVISIBLE (-3415 4035);
FORCEPROP 1 LASTPIN (-3425 4025) BN 7
J 0
(-3437 4033);
DISPLAY 0.489362 (-3437 4033);
PAINT GREEN (-3437 4033);
FORCEPROP 2 LAST CDS_LIB mstr_standard
J 0
(-3375 4025);
DISPLAY 0.723404 (-3375 4025);
PAINT MONO (-3375 4025);
DISPLAY INVISIBLE (-3375 4025);
FORCEPROP 1 LAST BODY_TYPE PLUMBING
J 0
(-3375 4075);
DISPLAY 0.872340 (-3375 4075);
PAINT GREEN (-3375 4075);
DISPLAY INVISIBLE (-3375 4075);
FORCEPROP 1 LAST HDL_TAP TRUE
J 0
(-3050 3900);
DISPLAY 0.872340 (-3050 3900);
DISPLAY INVISIBLE (-3050 3900);
FORCEPROP 1 LAST PATH I209
J 0
(-3377 4025);
DISPLAY 0.872340 (-3377 4025);
PAINT GREEN (-3377 4025);
DISPLAY INVISIBLE (-3377 4025);
FORCEADD OFFPAGE..1
(-8250 4975);
FORCEPROP 2 LAST $XR0 19 
J 0
(-8501 4975);
DISPLAY 0.638298 (-8501 4975);
PAINT MONO (-8501 4975);
FORCEPROP 2 LAST CDS_LIB mstr_standard
J 0
(-8250 4975);
DISPLAY 0.723404 (-8250 4975);
PAINT MONO (-8250 4975);
DISPLAY INVISIBLE (-8250 4975);
FORCEPROP 1 LAST OFFPAGE TRUE
J 0
(-7925 4850);
DISPLAY 0.872340 (-7925 4850);
PAINT GREEN (-7925 4850);
DISPLAY INVISIBLE (-7925 4850);
FORCEPROP 1 LAST COMMENT_BODY TRUE
J 0
(-8125 4875);
DISPLAY 0.872340 (-8125 4875);
PAINT GREEN (-8125 4875);
DISPLAY INVISIBLE (-8125 4875);
FORCEPROP 2 LAST PATH I21
J 0
(-8200 5050);
DISPLAY 1.021277 (-8200 5050);
DISPLAY INVISIBLE (-8200 5050);
FORCEADD TAP..1
(-3375 3925);
FORCEPROP 3 LASTPIN (-3425 3925) SIG_NAME M_J_CPU0_SA_DQS_DP<6>
J 0
(-3415 3935);
DISPLAY 0.659574 (-3415 3935);
PAINT MONO (-3415 3935);
DISPLAY INVISIBLE (-3415 3935);
FORCEPROP 1 LASTPIN (-3425 3925) BN 6
J 0
(-3437 3933);
DISPLAY 0.489362 (-3437 3933);
PAINT GREEN (-3437 3933);
FORCEPROP 2 LAST CDS_LIB mstr_standard
J 0
(-3375 3925);
DISPLAY 0.723404 (-3375 3925);
PAINT MONO (-3375 3925);
DISPLAY INVISIBLE (-3375 3925);
FORCEPROP 1 LAST BODY_TYPE PLUMBING
J 0
(-3375 3975);
DISPLAY 0.872340 (-3375 3975);
PAINT GREEN (-3375 3975);
DISPLAY INVISIBLE (-3375 3975);
FORCEPROP 1 LAST HDL_TAP TRUE
J 0
(-3050 3800);
DISPLAY 0.872340 (-3050 3800);
DISPLAY INVISIBLE (-3050 3800);
FORCEPROP 1 LAST PATH I210
J 0
(-3377 3925);
DISPLAY 0.872340 (-3377 3925);
PAINT GREEN (-3377 3925);
DISPLAY INVISIBLE (-3377 3925);
FORCEADD TAP..1
(-3375 3825);
FORCEPROP 3 LASTPIN (-3425 3825) SIG_NAME M_J_CPU0_SA_DQS_DP<5>
J 0
(-3415 3835);
DISPLAY 0.659574 (-3415 3835);
PAINT MONO (-3415 3835);
DISPLAY INVISIBLE (-3415 3835);
FORCEPROP 1 LASTPIN (-3425 3825) BN 5
J 0
(-3437 3833);
DISPLAY 0.489362 (-3437 3833);
PAINT GREEN (-3437 3833);
FORCEPROP 2 LAST CDS_LIB mstr_standard
J 0
(-3375 3825);
DISPLAY 0.723404 (-3375 3825);
PAINT MONO (-3375 3825);
DISPLAY INVISIBLE (-3375 3825);
FORCEPROP 1 LAST BODY_TYPE PLUMBING
J 0
(-3375 3875);
DISPLAY 0.872340 (-3375 3875);
PAINT GREEN (-3375 3875);
DISPLAY INVISIBLE (-3375 3875);
FORCEPROP 1 LAST HDL_TAP TRUE
J 0
(-3050 3700);
DISPLAY 0.872340 (-3050 3700);
DISPLAY INVISIBLE (-3050 3700);
FORCEPROP 1 LAST PATH I211
J 0
(-3377 3825);
DISPLAY 0.872340 (-3377 3825);
PAINT GREEN (-3377 3825);
DISPLAY INVISIBLE (-3377 3825);
FORCEADD TAP..1
(-3375 3725);
FORCEPROP 3 LASTPIN (-3425 3725) SIG_NAME M_J_CPU0_SA_DQS_DP<4>
J 0
(-3415 3735);
DISPLAY 0.659574 (-3415 3735);
PAINT MONO (-3415 3735);
DISPLAY INVISIBLE (-3415 3735);
FORCEPROP 1 LASTPIN (-3425 3725) BN 4
J 0
(-3437 3733);
DISPLAY 0.489362 (-3437 3733);
PAINT GREEN (-3437 3733);
FORCEPROP 2 LAST CDS_LIB mstr_standard
J 0
(-3375 3725);
DISPLAY 0.723404 (-3375 3725);
PAINT MONO (-3375 3725);
DISPLAY INVISIBLE (-3375 3725);
FORCEPROP 1 LAST BODY_TYPE PLUMBING
J 0
(-3375 3775);
DISPLAY 0.872340 (-3375 3775);
PAINT GREEN (-3375 3775);
DISPLAY INVISIBLE (-3375 3775);
FORCEPROP 1 LAST HDL_TAP TRUE
J 0
(-3050 3600);
DISPLAY 0.872340 (-3050 3600);
DISPLAY INVISIBLE (-3050 3600);
FORCEPROP 1 LAST PATH I212
J 0
(-3377 3725);
DISPLAY 0.872340 (-3377 3725);
PAINT GREEN (-3377 3725);
DISPLAY INVISIBLE (-3377 3725);
FORCEADD TAP..1
(-3375 3625);
FORCEPROP 3 LASTPIN (-3425 3625) SIG_NAME M_J_CPU0_SA_DQS_DP<3>
J 0
(-3415 3635);
DISPLAY 0.659574 (-3415 3635);
PAINT MONO (-3415 3635);
DISPLAY INVISIBLE (-3415 3635);
FORCEPROP 1 LASTPIN (-3425 3625) BN 3
J 0
(-3437 3633);
DISPLAY 0.489362 (-3437 3633);
PAINT GREEN (-3437 3633);
FORCEPROP 2 LAST CDS_LIB mstr_standard
J 0
(-3375 3625);
DISPLAY 0.723404 (-3375 3625);
PAINT MONO (-3375 3625);
DISPLAY INVISIBLE (-3375 3625);
FORCEPROP 1 LAST BODY_TYPE PLUMBING
J 0
(-3375 3675);
DISPLAY 0.872340 (-3375 3675);
PAINT GREEN (-3375 3675);
DISPLAY INVISIBLE (-3375 3675);
FORCEPROP 1 LAST HDL_TAP TRUE
J 0
(-3050 3500);
DISPLAY 0.872340 (-3050 3500);
DISPLAY INVISIBLE (-3050 3500);
FORCEPROP 1 LAST PATH I213
J 0
(-3377 3625);
DISPLAY 0.872340 (-3377 3625);
PAINT GREEN (-3377 3625);
DISPLAY INVISIBLE (-3377 3625);
FORCEADD TAP..1
(-3375 3525);
FORCEPROP 3 LASTPIN (-3425 3525) SIG_NAME M_J_CPU0_SA_DQS_DP<2>
J 0
(-3415 3535);
DISPLAY 0.659574 (-3415 3535);
PAINT MONO (-3415 3535);
DISPLAY INVISIBLE (-3415 3535);
FORCEPROP 1 LASTPIN (-3425 3525) BN 2
J 0
(-3437 3533);
DISPLAY 0.489362 (-3437 3533);
PAINT GREEN (-3437 3533);
FORCEPROP 2 LAST CDS_LIB mstr_standard
J 0
(-3375 3525);
DISPLAY 0.723404 (-3375 3525);
PAINT MONO (-3375 3525);
DISPLAY INVISIBLE (-3375 3525);
FORCEPROP 1 LAST BODY_TYPE PLUMBING
J 0
(-3375 3575);
DISPLAY 0.872340 (-3375 3575);
PAINT GREEN (-3375 3575);
DISPLAY INVISIBLE (-3375 3575);
FORCEPROP 1 LAST HDL_TAP TRUE
J 0
(-3050 3400);
DISPLAY 0.872340 (-3050 3400);
DISPLAY INVISIBLE (-3050 3400);
FORCEPROP 1 LAST PATH I214
J 0
(-3377 3525);
DISPLAY 0.872340 (-3377 3525);
PAINT GREEN (-3377 3525);
DISPLAY INVISIBLE (-3377 3525);
FORCEADD TAP..1
(-3375 3425);
FORCEPROP 3 LASTPIN (-3425 3425) SIG_NAME M_J_CPU0_SA_DQS_DP<1>
J 0
(-3415 3435);
DISPLAY 0.659574 (-3415 3435);
PAINT MONO (-3415 3435);
DISPLAY INVISIBLE (-3415 3435);
FORCEPROP 1 LASTPIN (-3425 3425) BN 1
J 0
(-3437 3433);
DISPLAY 0.489362 (-3437 3433);
PAINT GREEN (-3437 3433);
FORCEPROP 2 LAST CDS_LIB mstr_standard
J 0
(-3375 3425);
DISPLAY 0.723404 (-3375 3425);
PAINT MONO (-3375 3425);
DISPLAY INVISIBLE (-3375 3425);
FORCEPROP 1 LAST BODY_TYPE PLUMBING
J 0
(-3375 3475);
DISPLAY 0.872340 (-3375 3475);
PAINT GREEN (-3375 3475);
DISPLAY INVISIBLE (-3375 3475);
FORCEPROP 1 LAST HDL_TAP TRUE
J 0
(-3050 3300);
DISPLAY 0.872340 (-3050 3300);
DISPLAY INVISIBLE (-3050 3300);
FORCEPROP 1 LAST PATH I215
J 0
(-3377 3425);
DISPLAY 0.872340 (-3377 3425);
PAINT GREEN (-3377 3425);
DISPLAY INVISIBLE (-3377 3425);
FORCEADD TAP..1
(-3375 3325);
FORCEPROP 3 LASTPIN (-3425 3325) SIG_NAME M_J_CPU0_SA_DQS_DP<0>
J 0
(-3415 3335);
DISPLAY 0.659574 (-3415 3335);
PAINT MONO (-3415 3335);
DISPLAY INVISIBLE (-3415 3335);
FORCEPROP 1 LASTPIN (-3425 3325) BN 0
J 0
(-3437 3333);
DISPLAY 0.489362 (-3437 3333);
PAINT GREEN (-3437 3333);
FORCEPROP 2 LAST CDS_LIB mstr_standard
J 0
(-3375 3325);
DISPLAY 0.723404 (-3375 3325);
PAINT MONO (-3375 3325);
DISPLAY INVISIBLE (-3375 3325);
FORCEPROP 1 LAST BODY_TYPE PLUMBING
J 0
(-3375 3375);
DISPLAY 0.872340 (-3375 3375);
PAINT GREEN (-3375 3375);
DISPLAY INVISIBLE (-3375 3375);
FORCEPROP 1 LAST HDL_TAP TRUE
J 0
(-3050 3200);
DISPLAY 0.872340 (-3050 3200);
DISPLAY INVISIBLE (-3050 3200);
FORCEPROP 1 LAST PATH I216
J 0
(-3377 3325);
DISPLAY 0.872340 (-3377 3325);
PAINT GREEN (-3377 3325);
DISPLAY INVISIBLE (-3377 3325);
FORCEADD TAP..1
(-3375 3175);
FORCEPROP 3 LASTPIN (-3425 3175) SIG_NAME M_J_CPU0_SB_DQS_DP<9>
J 0
(-3415 3185);
DISPLAY 0.659574 (-3415 3185);
PAINT MONO (-3415 3185);
DISPLAY INVISIBLE (-3415 3185);
FORCEPROP 1 LASTPIN (-3425 3175) BN 9
J 0
(-3437 3183);
DISPLAY 0.489362 (-3437 3183);
PAINT GREEN (-3437 3183);
FORCEPROP 2 LAST CDS_LIB mstr_standard
J 0
(-3375 3175);
DISPLAY 0.723404 (-3375 3175);
PAINT MONO (-3375 3175);
DISPLAY INVISIBLE (-3375 3175);
FORCEPROP 1 LAST BODY_TYPE PLUMBING
J 0
(-3375 3225);
DISPLAY 0.872340 (-3375 3225);
PAINT GREEN (-3375 3225);
DISPLAY INVISIBLE (-3375 3225);
FORCEPROP 1 LAST HDL_TAP TRUE
J 0
(-3050 3050);
DISPLAY 0.872340 (-3050 3050);
DISPLAY INVISIBLE (-3050 3050);
FORCEPROP 1 LAST PATH I217
J 0
(-3377 3175);
DISPLAY 0.872340 (-3377 3175);
PAINT GREEN (-3377 3175);
DISPLAY INVISIBLE (-3377 3175);
FORCEADD TAP..1
(-3375 3075);
FORCEPROP 3 LASTPIN (-3425 3075) SIG_NAME M_J_CPU0_SB_DQS_DP<8>
J 0
(-3415 3085);
DISPLAY 0.659574 (-3415 3085);
PAINT MONO (-3415 3085);
DISPLAY INVISIBLE (-3415 3085);
FORCEPROP 1 LASTPIN (-3425 3075) BN 8
J 0
(-3437 3083);
DISPLAY 0.489362 (-3437 3083);
PAINT GREEN (-3437 3083);
FORCEPROP 2 LAST CDS_LIB mstr_standard
J 0
(-3375 3075);
DISPLAY 0.723404 (-3375 3075);
PAINT MONO (-3375 3075);
DISPLAY INVISIBLE (-3375 3075);
FORCEPROP 1 LAST BODY_TYPE PLUMBING
J 0
(-3375 3125);
DISPLAY 0.872340 (-3375 3125);
PAINT GREEN (-3375 3125);
DISPLAY INVISIBLE (-3375 3125);
FORCEPROP 1 LAST HDL_TAP TRUE
J 0
(-3050 2950);
DISPLAY 0.872340 (-3050 2950);
DISPLAY INVISIBLE (-3050 2950);
FORCEPROP 1 LAST PATH I218
J 0
(-3377 3075);
DISPLAY 0.872340 (-3377 3075);
PAINT GREEN (-3377 3075);
DISPLAY INVISIBLE (-3377 3075);
FORCEADD TAP..1
(-3175 2925);
FORCEPROP 3 LASTPIN (-3225 2925) SIG_NAME M_J_CPU0_SB_DQS_DN<7>
J 0
(-3215 2935);
DISPLAY 0.659574 (-3215 2935);
PAINT MONO (-3215 2935);
DISPLAY INVISIBLE (-3215 2935);
FORCEPROP 1 LASTPIN (-3225 2925) BN 7
J 0
(-3237 2933);
DISPLAY 0.489362 (-3237 2933);
PAINT GREEN (-3237 2933);
FORCEPROP 2 LAST CDS_LIB mstr_standard
J 0
(-3175 2925);
DISPLAY 0.723404 (-3175 2925);
PAINT MONO (-3175 2925);
DISPLAY INVISIBLE (-3175 2925);
FORCEPROP 1 LAST BODY_TYPE PLUMBING
J 0
(-3175 2975);
DISPLAY 0.872340 (-3175 2975);
PAINT GREEN (-3175 2975);
DISPLAY INVISIBLE (-3175 2975);
FORCEPROP 1 LAST HDL_TAP TRUE
J 0
(-2850 2800);
DISPLAY 0.872340 (-2850 2800);
DISPLAY INVISIBLE (-2850 2800);
FORCEPROP 1 LAST PATH I219
J 0
(-3177 2925);
DISPLAY 0.872340 (-3177 2925);
PAINT GREEN (-3177 2925);
DISPLAY INVISIBLE (-3177 2925);
FORCEADD SCONN288_DDR506112002KQ..1
(-6800 3575);
FORCEPROP 1 LAST LOCATION J68
J 0
(-7250 5650);
DISPLAY 0.468085 (-7250 5650);
PAINT SKYBLUE (-7250 5650);
FORCEPROP 0 LAST $SEC 1
J 0
(-7250 5800);
DISPLAY 0.680851 (-7250 5800);
PAINT MONO (-7250 5800);
DISPLAY INVISIBLE (-7250 5800);
FORCEPROP 2 LAST CDS_SEC 1
J 0
(-7250 5800);
DISPLAY 1.021277 (-7250 5800);
DISPLAY INVISIBLE (-7250 5800);
FORCEPROP 0 LASTPIN (-7400 2975) $PN 62
J 2
(-7410 2985);
DISPLAY 0.680851 (-7410 2985);
PAINT MONO (-7410 2985);
FORCEPROP 0 LASTPIN (-7400 5025) $PN 66
J 2
(-7410 5035);
DISPLAY 0.680851 (-7410 5035);
PAINT MONO (-7410 5035);
FORCEPROP 0 LASTPIN (-7400 4625) $PN 76
J 2
(-7410 4635);
DISPLAY 0.680851 (-7410 4635);
PAINT MONO (-7410 4635);
FORCEPROP 0 LASTPIN (-7400 5075) $PN 211
J 2
(-7410 5085);
DISPLAY 0.680851 (-7410 5085);
PAINT MONO (-7410 5085);
FORCEPROP 0 LASTPIN (-7400 4675) $PN 221
J 2
(-7410 4685);
DISPLAY 0.680851 (-7410 4685);
PAINT MONO (-7410 4685);
FORCEPROP 0 LASTPIN (-7400 5125) $PN 68
J 2
(-7410 5135);
DISPLAY 0.680851 (-7410 5135);
PAINT MONO (-7410 5135);
FORCEPROP 0 LASTPIN (-7400 4725) $PN 78
J 2
(-7410 4735);
DISPLAY 0.680851 (-7410 4735);
PAINT MONO (-7410 4735);
FORCEPROP 0 LASTPIN (-7400 5175) $PN 213
J 2
(-7410 5185);
DISPLAY 0.680851 (-7410 5185);
PAINT MONO (-7410 5185);
FORCEPROP 0 LASTPIN (-7400 4775) $PN 223
J 2
(-7410 4785);
DISPLAY 0.680851 (-7410 4785);
PAINT MONO (-7410 4785);
FORCEPROP 0 LASTPIN (-7400 5225) $PN 70
J 2
(-7410 5235);
DISPLAY 0.680851 (-7410 5235);
PAINT MONO (-7410 5235);
FORCEPROP 0 LASTPIN (-7400 4825) $PN 80
J 2
(-7410 4835);
DISPLAY 0.680851 (-7410 4835);
PAINT MONO (-7410 4835);
FORCEPROP 0 LASTPIN (-7400 5275) $PN 215
J 2
(-7410 5285);
DISPLAY 0.680851 (-7410 5285);
PAINT MONO (-7410 5285);
FORCEPROP 0 LASTPIN (-7400 4875) $PN 225
J 2
(-7410 4885);
DISPLAY 0.680851 (-7410 4885);
PAINT MONO (-7410 4885);
FORCEPROP 0 LASTPIN (-7400 5325) $PN 72
J 2
(-7410 5335);
DISPLAY 0.680851 (-7410 5335);
PAINT MONO (-7410 5335);
FORCEPROP 0 LASTPIN (-7400 4925) $PN 82
J 2
(-7410 4935);
DISPLAY 0.680851 (-7410 4935);
PAINT MONO (-7410 4935);
FORCEPROP 0 LASTPIN (-7400 3575) $PN 51
J 2
(-7410 3585);
DISPLAY 0.680851 (-7410 3585);
PAINT MONO (-7410 3585);
FORCEPROP 0 LASTPIN (-7400 3125) $PN 96
J 2
(-7410 3135);
DISPLAY 0.680851 (-7410 3135);
PAINT MONO (-7410 3135);
FORCEPROP 0 LASTPIN (-7400 3625) $PN 53
J 2
(-7410 3635);
DISPLAY 0.680851 (-7410 3635);
PAINT MONO (-7410 3635);
FORCEPROP 0 LASTPIN (-7400 3175) $PN 98
J 2
(-7410 3185);
DISPLAY 0.680851 (-7410 3185);
PAINT MONO (-7410 3185);
FORCEPROP 0 LASTPIN (-7400 3675) $PN 196
J 2
(-7410 3685);
DISPLAY 0.680851 (-7410 3685);
PAINT MONO (-7410 3685);
FORCEPROP 0 LASTPIN (-7400 3225) $PN 241
J 2
(-7410 3235);
DISPLAY 0.680851 (-7410 3235);
PAINT MONO (-7410 3235);
FORCEPROP 0 LASTPIN (-7400 3725) $PN 198
J 2
(-7410 3735);
DISPLAY 0.680851 (-7410 3735);
PAINT MONO (-7410 3735);
FORCEPROP 0 LASTPIN (-7400 3275) $PN 243
J 2
(-7410 3285);
DISPLAY 0.680851 (-7410 3285);
PAINT MONO (-7410 3285);
FORCEPROP 0 LASTPIN (-7400 3775) $PN 58
J 2
(-7410 3785);
DISPLAY 0.680851 (-7410 3785);
PAINT MONO (-7410 3785);
FORCEPROP 0 LASTPIN (-7400 3325) $PN 89
J 2
(-7410 3335);
DISPLAY 0.680851 (-7410 3335);
PAINT MONO (-7410 3335);
FORCEPROP 0 LASTPIN (-7400 3825) $PN 60
J 2
(-7410 3835);
DISPLAY 0.680851 (-7410 3835);
PAINT MONO (-7410 3835);
FORCEPROP 0 LASTPIN (-7400 3375) $PN 91
J 2
(-7410 3385);
DISPLAY 0.680851 (-7410 3385);
PAINT MONO (-7410 3385);
FORCEPROP 0 LASTPIN (-7400 3875) $PN 203
J 2
(-7410 3885);
DISPLAY 0.680851 (-7410 3885);
PAINT MONO (-7410 3885);
FORCEPROP 0 LASTPIN (-7400 3425) $PN 234
J 2
(-7410 3435);
DISPLAY 0.680851 (-7410 3435);
PAINT MONO (-7410 3435);
FORCEPROP 0 LASTPIN (-7400 3925) $PN 205
J 2
(-7410 3935);
DISPLAY 0.680851 (-7410 3935);
PAINT MONO (-7410 3935);
FORCEPROP 0 LASTPIN (-7400 3475) $PN 236
J 2
(-7410 3485);
DISPLAY 0.680851 (-7410 3485);
PAINT MONO (-7410 3485);
FORCEPROP 0 LASTPIN (-7400 4025) $PN 218
J 2
(-7410 4035);
DISPLAY 0.680851 (-7410 4035);
PAINT MONO (-7410 4035);
FORCEPROP 0 LASTPIN (-7400 4075) $PN 217
J 2
(-7410 4085);
DISPLAY 0.680851 (-7410 4085);
PAINT MONO (-7410 4085);
FORCEPROP 0 LASTPIN (-7400 4325) $PN 64
J 2
(-7410 4335);
DISPLAY 0.680851 (-7410 4335);
PAINT MONO (-7410 4335);
FORCEPROP 0 LASTPIN (-7400 4175) $PN 84
J 2
(-7410 4185);
DISPLAY 0.680851 (-7410 4185);
PAINT MONO (-7410 4185);
FORCEPROP 0 LASTPIN (-7400 4375) $PN 209
J 2
(-7410 4385);
DISPLAY 0.680851 (-7410 4385);
PAINT MONO (-7410 4385);
FORCEPROP 0 LASTPIN (-7400 4225) $PN 229
J 2
(-7410 4235);
DISPLAY 0.680851 (-7410 4235);
PAINT MONO (-7410 4235);
FORCEPROP 0 LASTPIN (-6200 3775) $PN 7
J 0
(-6190 3785);
DISPLAY 0.680851 (-6190 3785);
PAINT MONO (-6190 3785);
FORCEPROP 0 LASTPIN (-6200 2125) $PN 100
J 0
(-6190 2135);
DISPLAY 0.680851 (-6190 2135);
PAINT MONO (-6190 2135);
FORCEPROP 0 LASTPIN (-6200 3825) $PN 9
J 0
(-6190 3835);
DISPLAY 0.680851 (-6190 3835);
PAINT MONO (-6190 3835);
FORCEPROP 0 LASTPIN (-6200 2175) $PN 102
J 0
(-6190 2185);
DISPLAY 0.680851 (-6190 2185);
PAINT MONO (-6190 2185);
FORCEPROP 0 LASTPIN (-6200 3875) $PN 152
J 0
(-6190 3885);
DISPLAY 0.680851 (-6190 3885);
PAINT MONO (-6190 3885);
FORCEPROP 0 LASTPIN (-6200 2225) $PN 245
J 0
(-6190 2235);
DISPLAY 0.680851 (-6190 2235);
PAINT MONO (-6190 2235);
FORCEPROP 0 LASTPIN (-6200 3925) $PN 154
J 0
(-6190 3935);
DISPLAY 0.680851 (-6190 3935);
PAINT MONO (-6190 3935);
FORCEPROP 0 LASTPIN (-6200 2275) $PN 247
J 0
(-6190 2285);
DISPLAY 0.680851 (-6190 2285);
PAINT MONO (-6190 2285);
FORCEPROP 0 LASTPIN (-6200 3975) $PN 14
J 0
(-6190 3985);
DISPLAY 0.680851 (-6190 3985);
PAINT MONO (-6190 3985);
FORCEPROP 0 LASTPIN (-6200 2325) $PN 107
J 0
(-6190 2335);
DISPLAY 0.680851 (-6190 2335);
PAINT MONO (-6190 2335);
FORCEPROP 0 LASTPIN (-6200 4025) $PN 16
J 0
(-6190 4035);
DISPLAY 0.680851 (-6190 4035);
PAINT MONO (-6190 4035);
FORCEPROP 0 LASTPIN (-6200 2375) $PN 109
J 0
(-6190 2385);
DISPLAY 0.680851 (-6190 2385);
PAINT MONO (-6190 2385);
FORCEPROP 0 LASTPIN (-6200 4075) $PN 159
J 0
(-6190 4085);
DISPLAY 0.680851 (-6190 4085);
PAINT MONO (-6190 4085);
FORCEPROP 0 LASTPIN (-6200 2425) $PN 252
J 0
(-6190 2435);
DISPLAY 0.680851 (-6190 2435);
PAINT MONO (-6190 2435);
FORCEPROP 0 LASTPIN (-6200 4125) $PN 161
J 0
(-6190 4135);
DISPLAY 0.680851 (-6190 4135);
PAINT MONO (-6190 4135);
FORCEPROP 0 LASTPIN (-6200 2475) $PN 254
J 0
(-6190 2485);
DISPLAY 0.680851 (-6190 2485);
PAINT MONO (-6190 2485);
FORCEPROP 0 LASTPIN (-6200 4175) $PN 18
J 0
(-6190 4185);
DISPLAY 0.680851 (-6190 4185);
PAINT MONO (-6190 4185);
FORCEPROP 0 LASTPIN (-6200 2525) $PN 111
J 0
(-6190 2535);
DISPLAY 0.680851 (-6190 2535);
PAINT MONO (-6190 2535);
FORCEPROP 0 LASTPIN (-6200 4225) $PN 20
J 0
(-6190 4235);
DISPLAY 0.680851 (-6190 4235);
PAINT MONO (-6190 4235);
FORCEPROP 0 LASTPIN (-6200 2575) $PN 113
J 0
(-6190 2585);
DISPLAY 0.680851 (-6190 2585);
PAINT MONO (-6190 2585);
FORCEPROP 0 LASTPIN (-6200 4275) $PN 163
J 0
(-6190 4285);
DISPLAY 0.680851 (-6190 4285);
PAINT MONO (-6190 4285);
FORCEPROP 0 LASTPIN (-6200 2625) $PN 256
J 0
(-6190 2635);
DISPLAY 0.680851 (-6190 2635);
PAINT MONO (-6190 2635);
FORCEPROP 0 LASTPIN (-6200 4325) $PN 165
J 0
(-6190 4335);
DISPLAY 0.680851 (-6190 4335);
PAINT MONO (-6190 4335);
FORCEPROP 0 LASTPIN (-6200 2675) $PN 258
J 0
(-6190 2685);
DISPLAY 0.680851 (-6190 2685);
PAINT MONO (-6190 2685);
FORCEPROP 0 LASTPIN (-6200 4375) $PN 25
J 0
(-6190 4385);
DISPLAY 0.680851 (-6190 4385);
PAINT MONO (-6190 4385);
FORCEPROP 0 LASTPIN (-6200 2725) $PN 118
J 0
(-6190 2735);
DISPLAY 0.680851 (-6190 2735);
PAINT MONO (-6190 2735);
FORCEPROP 0 LASTPIN (-6200 4425) $PN 27
J 0
(-6190 4435);
DISPLAY 0.680851 (-6190 4435);
PAINT MONO (-6190 4435);
FORCEPROP 0 LASTPIN (-6200 2775) $PN 120
J 0
(-6190 2785);
DISPLAY 0.680851 (-6190 2785);
PAINT MONO (-6190 2785);
FORCEPROP 0 LASTPIN (-6200 4475) $PN 170
J 0
(-6190 4485);
DISPLAY 0.680851 (-6190 4485);
PAINT MONO (-6190 4485);
FORCEPROP 0 LASTPIN (-6200 2825) $PN 263
J 0
(-6190 2835);
DISPLAY 0.680851 (-6190 2835);
PAINT MONO (-6190 2835);
FORCEPROP 0 LASTPIN (-6200 4525) $PN 172
J 0
(-6190 4535);
DISPLAY 0.680851 (-6190 4535);
PAINT MONO (-6190 4535);
FORCEPROP 0 LASTPIN (-6200 2875) $PN 265
J 0
(-6190 2885);
DISPLAY 0.680851 (-6190 2885);
PAINT MONO (-6190 2885);
FORCEPROP 0 LASTPIN (-6200 4575) $PN 29
J 0
(-6190 4585);
DISPLAY 0.680851 (-6190 4585);
PAINT MONO (-6190 4585);
FORCEPROP 0 LASTPIN (-6200 2925) $PN 122
J 0
(-6190 2935);
DISPLAY 0.680851 (-6190 2935);
PAINT MONO (-6190 2935);
FORCEPROP 0 LASTPIN (-6200 4625) $PN 31
J 0
(-6190 4635);
DISPLAY 0.680851 (-6190 4635);
PAINT MONO (-6190 4635);
FORCEPROP 0 LASTPIN (-6200 2975) $PN 124
J 0
(-6190 2985);
DISPLAY 0.680851 (-6190 2985);
PAINT MONO (-6190 2985);
FORCEPROP 0 LASTPIN (-6200 4675) $PN 174
J 0
(-6190 4685);
DISPLAY 0.680851 (-6190 4685);
PAINT MONO (-6190 4685);
FORCEPROP 0 LASTPIN (-6200 3025) $PN 267
J 0
(-6190 3035);
DISPLAY 0.680851 (-6190 3035);
PAINT MONO (-6190 3035);
FORCEPROP 0 LASTPIN (-6200 4725) $PN 176
J 0
(-6190 4735);
DISPLAY 0.680851 (-6190 4735);
PAINT MONO (-6190 4735);
FORCEPROP 0 LASTPIN (-6200 3075) $PN 269
J 0
(-6190 3085);
DISPLAY 0.680851 (-6190 3085);
PAINT MONO (-6190 3085);
FORCEPROP 0 LASTPIN (-6200 4775) $PN 36
J 0
(-6190 4785);
DISPLAY 0.680851 (-6190 4785);
PAINT MONO (-6190 4785);
FORCEPROP 0 LASTPIN (-6200 3125) $PN 129
J 0
(-6190 3135);
DISPLAY 0.680851 (-6190 3135);
PAINT MONO (-6190 3135);
FORCEPROP 0 LASTPIN (-6200 4825) $PN 38
J 0
(-6190 4835);
DISPLAY 0.680851 (-6190 4835);
PAINT MONO (-6190 4835);
FORCEPROP 0 LASTPIN (-6200 3175) $PN 131
J 0
(-6190 3185);
DISPLAY 0.680851 (-6190 3185);
PAINT MONO (-6190 3185);
FORCEPROP 0 LASTPIN (-6200 4875) $PN 181
J 0
(-6190 4885);
DISPLAY 0.680851 (-6190 4885);
PAINT MONO (-6190 4885);
FORCEPROP 0 LASTPIN (-6200 3225) $PN 274
J 0
(-6190 3235);
DISPLAY 0.680851 (-6190 3235);
PAINT MONO (-6190 3235);
FORCEPROP 0 LASTPIN (-6200 4925) $PN 183
J 0
(-6190 4935);
DISPLAY 0.680851 (-6190 4935);
PAINT MONO (-6190 4935);
FORCEPROP 0 LASTPIN (-6200 3275) $PN 276
J 0
(-6190 3285);
DISPLAY 0.680851 (-6190 3285);
PAINT MONO (-6190 3285);
FORCEPROP 0 LASTPIN (-6200 4975) $PN 40
J 0
(-6190 4985);
DISPLAY 0.680851 (-6190 4985);
PAINT MONO (-6190 4985);
FORCEPROP 0 LASTPIN (-6200 3325) $PN 133
J 0
(-6190 3335);
DISPLAY 0.680851 (-6190 3335);
PAINT MONO (-6190 3335);
FORCEPROP 0 LASTPIN (-6200 5025) $PN 42
J 0
(-6190 5035);
DISPLAY 0.680851 (-6190 5035);
PAINT MONO (-6190 5035);
FORCEPROP 0 LASTPIN (-6200 3375) $PN 135
J 0
(-6190 3385);
DISPLAY 0.680851 (-6190 3385);
PAINT MONO (-6190 3385);
FORCEPROP 0 LASTPIN (-6200 5075) $PN 185
J 0
(-6190 5085);
DISPLAY 0.680851 (-6190 5085);
PAINT MONO (-6190 5085);
FORCEPROP 0 LASTPIN (-6200 3425) $PN 278
J 0
(-6190 3435);
DISPLAY 0.680851 (-6190 3435);
PAINT MONO (-6190 3435);
FORCEPROP 0 LASTPIN (-6200 5125) $PN 187
J 0
(-6190 5135);
DISPLAY 0.680851 (-6190 5135);
PAINT MONO (-6190 5135);
FORCEPROP 0 LASTPIN (-6200 3475) $PN 280
J 0
(-6190 3485);
DISPLAY 0.680851 (-6190 3485);
PAINT MONO (-6190 3485);
FORCEPROP 0 LASTPIN (-6200 5175) $PN 47
J 0
(-6190 5185);
DISPLAY 0.680851 (-6190 5185);
PAINT MONO (-6190 5185);
FORCEPROP 0 LASTPIN (-6200 3525) $PN 140
J 0
(-6190 3535);
DISPLAY 0.680851 (-6190 3535);
PAINT MONO (-6190 3535);
FORCEPROP 0 LASTPIN (-6200 5225) $PN 49
J 0
(-6190 5235);
DISPLAY 0.680851 (-6190 5235);
PAINT MONO (-6190 5235);
FORCEPROP 0 LASTPIN (-6200 3575) $PN 142
J 0
(-6190 3585);
DISPLAY 0.680851 (-6190 3585);
PAINT MONO (-6190 3585);
FORCEPROP 0 LASTPIN (-6200 5275) $PN 192
J 0
(-6190 5285);
DISPLAY 0.680851 (-6190 5285);
PAINT MONO (-6190 5285);
FORCEPROP 0 LASTPIN (-6200 3625) $PN 285
J 0
(-6190 3635);
DISPLAY 0.680851 (-6190 3635);
PAINT MONO (-6190 3635);
FORCEPROP 0 LASTPIN (-6200 5325) $PN 194
J 0
(-6190 5335);
DISPLAY 0.680851 (-6190 5335);
PAINT MONO (-6190 5335);
FORCEPROP 0 LASTPIN (-6200 3675) $PN 287
J 0
(-6190 3685);
DISPLAY 0.680851 (-6190 3685);
PAINT MONO (-6190 3685);
FORCEPROP 0 LASTPIN (-7400 2825) $PN 148
J 2
(-7410 2835);
DISPLAY 0.680851 (-7410 2835);
PAINT MONO (-7410 2835);
FORCEPROP 0 LASTPIN (-7400 2725) $PN 4
J 2
(-7410 2735);
DISPLAY 0.680851 (-7410 2735);
PAINT MONO (-7410 2735);
FORCEPROP 0 LASTPIN (-7400 2775) $PN 5
J 2
(-7410 2785);
DISPLAY 0.680851 (-7410 2785);
PAINT MONO (-7410 2785);
FORCEPROP 0 LASTPIN (-7400 1925) $PN 86
J 2
(-7410 1935);
DISPLAY 0.680851 (-7410 1935);
PAINT MONO (-7410 1935);
FORCEPROP 0 LASTPIN (-7400 1875) $PN 87
J 2
(-7410 1885);
DISPLAY 0.680851 (-7410 1885);
PAINT MONO (-7410 1885);
FORCEPROP 0 LASTPIN (-7400 4525) $PN 74
J 2
(-7410 4535);
DISPLAY 0.680851 (-7410 4535);
PAINT MONO (-7410 4535);
FORCEPROP 0 LASTPIN (-7400 4475) $PN 227
J 2
(-7410 4485);
DISPLAY 0.680851 (-7410 4485);
PAINT MONO (-7410 4485);
FORCEPROP 0 LASTPIN (-7400 2475) $PN 147
J 2
(-7410 2485);
DISPLAY 0.680851 (-7410 2485);
PAINT MONO (-7410 2485);
FORCEPROP 0 LASTPIN (-7400 3025) $PN 207
J 2
(-7410 3035);
DISPLAY 0.680851 (-7410 3035);
PAINT MONO (-7410 3035);
FORCEPROP 0 LASTPIN (-7400 2075) $PN 2
J 2
(-7410 2085);
DISPLAY 0.680851 (-7410 2085);
PAINT MONO (-7410 2085);
FORCEPROP 0 LASTPIN (-7400 2125) $PN 144
J 2
(-7410 2135);
DISPLAY 0.680851 (-7410 2135);
PAINT MONO (-7410 2135);
FORCEPROP 0 LASTPIN (-7400 2175) $PN 149
J 2
(-7410 2185);
DISPLAY 0.680851 (-7410 2185);
PAINT MONO (-7410 2185);
FORCEPROP 0 LASTPIN (-7400 2225) $PN 150
J 2
(-7410 2235);
DISPLAY 0.680851 (-7410 2235);
PAINT MONO (-7410 2235);
FORCEPROP 0 LASTPIN (-7400 2275) $PN 220
J 2
(-7410 2285);
DISPLAY 0.680851 (-7410 2285);
PAINT MONO (-7410 2285);
FORCEPROP 0 LASTPIN (-7400 2325) $PN 231
J 2
(-7410 2335);
DISPLAY 0.680851 (-7410 2335);
PAINT MONO (-7410 2335);
FORCEPROP 0 LASTPIN (-7400 2375) $PN 232
J 2
(-7410 2385);
DISPLAY 0.680851 (-7410 2385);
PAINT MONO (-7410 2385);
FORCEPROP 0 LASTPIN (-7400 2875) $PN 3
J 2
(-7410 2885);
DISPLAY 0.680851 (-7410 2885);
PAINT MONO (-7410 2885);
FORCEPROP 1 LAST MATERIAL IO
J 0
(-7250 5500);
DISPLAY 0.468085 (-7250 5500);
PAINT SKYBLUE (-7250 5500);
FORCEPROP 2 LAST VALUE SCONN288_DDR506112002KQ
J 0
(-7250 5700);
DISPLAY 0.489362 (-7250 5700);
PAINT SKYBLUE (-7250 5700);
FORCEPROP 2 LAST PART_TYPE SMLF
J 0
(-7250 5750);
DISPLAY 1.021277 (-7250 5750);
FORCEPROP 1 LAST CDS_LMAN_SYM_OUTLINE -450,1900,450,-1850
J 0
(-6800 3575);
DISPLAY 0.468085 (-6800 3575);
PAINT GREEN (-6800 3575);
DISPLAY INVISIBLE (-6800 3575);
FORCEPROP 1 LAST NEEDS_NO_SIZE TRUE
J 0
(-6800 3575);
DISPLAY 0.723404 (-6800 3575);
PAINT GREEN (-6800 3575);
DISPLAY INVISIBLE (-6800 3575);
FORCEPROP 2 LAST CDS_LIB pure_quanta
J 0
(-6800 3575);
DISPLAY INVISIBLE (-6800 3575);
FORCEPROP 1 LAST PATH I22
J 0
(-6800 3575);
DISPLAY 0.723404 (-6800 3575);
PAINT GREEN (-6800 3575);
DISPLAY INVISIBLE (-6800 3575);
FORCEPROP 1 LAST PART_NUMBER DFHST8FS479
J 0
(-7250 5575);
DISPLAY 0.468085 (-7250 5575);
PAINT SKYBLUE (-7250 5575);
DISPLAY INVISIBLE (-7250 5575);
FORCEADD TAP..1
(-3175 3025);
FORCEPROP 3 LASTPIN (-3225 3025) SIG_NAME M_J_CPU0_SB_DQS_DN<8>
J 0
(-3215 3035);
DISPLAY 0.659574 (-3215 3035);
PAINT MONO (-3215 3035);
DISPLAY INVISIBLE (-3215 3035);
FORCEPROP 1 LASTPIN (-3225 3025) BN 8
J 0
(-3237 3033);
DISPLAY 0.489362 (-3237 3033);
PAINT GREEN (-3237 3033);
FORCEPROP 2 LAST CDS_LIB mstr_standard
J 0
(-3175 3025);
DISPLAY 0.723404 (-3175 3025);
PAINT MONO (-3175 3025);
DISPLAY INVISIBLE (-3175 3025);
FORCEPROP 1 LAST BODY_TYPE PLUMBING
J 0
(-3175 3075);
DISPLAY 0.872340 (-3175 3075);
PAINT GREEN (-3175 3075);
DISPLAY INVISIBLE (-3175 3075);
FORCEPROP 1 LAST HDL_TAP TRUE
J 0
(-2850 2900);
DISPLAY 0.872340 (-2850 2900);
DISPLAY INVISIBLE (-2850 2900);
FORCEPROP 1 LAST PATH I220
J 0
(-3177 3025);
DISPLAY 0.872340 (-3177 3025);
PAINT GREEN (-3177 3025);
DISPLAY INVISIBLE (-3177 3025);
FORCEADD TAP..1
(-3175 2825);
FORCEPROP 3 LASTPIN (-3225 2825) SIG_NAME M_J_CPU0_SB_DQS_DN<6>
J 0
(-3215 2835);
DISPLAY 0.659574 (-3215 2835);
PAINT MONO (-3215 2835);
DISPLAY INVISIBLE (-3215 2835);
FORCEPROP 1 LASTPIN (-3225 2825) BN 6
J 0
(-3237 2833);
DISPLAY 0.489362 (-3237 2833);
PAINT GREEN (-3237 2833);
FORCEPROP 2 LAST CDS_LIB mstr_standard
J 0
(-3175 2825);
DISPLAY 0.723404 (-3175 2825);
PAINT MONO (-3175 2825);
DISPLAY INVISIBLE (-3175 2825);
FORCEPROP 1 LAST BODY_TYPE PLUMBING
J 0
(-3175 2875);
DISPLAY 0.872340 (-3175 2875);
PAINT GREEN (-3175 2875);
DISPLAY INVISIBLE (-3175 2875);
FORCEPROP 1 LAST HDL_TAP TRUE
J 0
(-2850 2700);
DISPLAY 0.872340 (-2850 2700);
DISPLAY INVISIBLE (-2850 2700);
FORCEPROP 1 LAST PATH I221
J 0
(-3177 2825);
DISPLAY 0.872340 (-3177 2825);
PAINT GREEN (-3177 2825);
DISPLAY INVISIBLE (-3177 2825);
FORCEADD TAP..1
(-3175 2625);
FORCEPROP 3 LASTPIN (-3225 2625) SIG_NAME M_J_CPU0_SB_DQS_DN<4>
J 0
(-3215 2635);
DISPLAY 0.659574 (-3215 2635);
PAINT MONO (-3215 2635);
DISPLAY INVISIBLE (-3215 2635);
FORCEPROP 1 LASTPIN (-3225 2625) BN 4
J 0
(-3237 2633);
DISPLAY 0.489362 (-3237 2633);
PAINT GREEN (-3237 2633);
FORCEPROP 2 LAST CDS_LIB mstr_standard
J 0
(-3175 2625);
DISPLAY 0.723404 (-3175 2625);
PAINT MONO (-3175 2625);
DISPLAY INVISIBLE (-3175 2625);
FORCEPROP 1 LAST BODY_TYPE PLUMBING
J 0
(-3175 2675);
DISPLAY 0.872340 (-3175 2675);
PAINT GREEN (-3175 2675);
DISPLAY INVISIBLE (-3175 2675);
FORCEPROP 1 LAST HDL_TAP TRUE
J 0
(-2850 2500);
DISPLAY 0.872340 (-2850 2500);
DISPLAY INVISIBLE (-2850 2500);
FORCEPROP 1 LAST PATH I222
J 0
(-3177 2625);
DISPLAY 0.872340 (-3177 2625);
PAINT GREEN (-3177 2625);
DISPLAY INVISIBLE (-3177 2625);
FORCEADD TAP..1
(-3175 2725);
FORCEPROP 3 LASTPIN (-3225 2725) SIG_NAME M_J_CPU0_SB_DQS_DN<5>
J 0
(-3215 2735);
DISPLAY 0.659574 (-3215 2735);
PAINT MONO (-3215 2735);
DISPLAY INVISIBLE (-3215 2735);
FORCEPROP 1 LASTPIN (-3225 2725) BN 5
J 0
(-3237 2733);
DISPLAY 0.489362 (-3237 2733);
PAINT GREEN (-3237 2733);
FORCEPROP 2 LAST CDS_LIB mstr_standard
J 0
(-3175 2725);
DISPLAY 0.723404 (-3175 2725);
PAINT MONO (-3175 2725);
DISPLAY INVISIBLE (-3175 2725);
FORCEPROP 1 LAST BODY_TYPE PLUMBING
J 0
(-3175 2775);
DISPLAY 0.872340 (-3175 2775);
PAINT GREEN (-3175 2775);
DISPLAY INVISIBLE (-3175 2775);
FORCEPROP 1 LAST HDL_TAP TRUE
J 0
(-2850 2600);
DISPLAY 0.872340 (-2850 2600);
DISPLAY INVISIBLE (-2850 2600);
FORCEPROP 1 LAST PATH I223
J 0
(-3177 2725);
DISPLAY 0.872340 (-3177 2725);
PAINT GREEN (-3177 2725);
DISPLAY INVISIBLE (-3177 2725);
FORCEADD TAP..1
(-3175 2525);
FORCEPROP 3 LASTPIN (-3225 2525) SIG_NAME M_J_CPU0_SB_DQS_DN<3>
J 0
(-3215 2535);
DISPLAY 0.659574 (-3215 2535);
PAINT MONO (-3215 2535);
DISPLAY INVISIBLE (-3215 2535);
FORCEPROP 1 LASTPIN (-3225 2525) BN 3
J 0
(-3237 2533);
DISPLAY 0.489362 (-3237 2533);
PAINT GREEN (-3237 2533);
FORCEPROP 2 LAST CDS_LIB mstr_standard
J 0
(-3175 2525);
DISPLAY 0.723404 (-3175 2525);
PAINT MONO (-3175 2525);
DISPLAY INVISIBLE (-3175 2525);
FORCEPROP 1 LAST BODY_TYPE PLUMBING
J 0
(-3175 2575);
DISPLAY 0.872340 (-3175 2575);
PAINT GREEN (-3175 2575);
DISPLAY INVISIBLE (-3175 2575);
FORCEPROP 1 LAST HDL_TAP TRUE
J 0
(-2850 2400);
DISPLAY 0.872340 (-2850 2400);
DISPLAY INVISIBLE (-2850 2400);
FORCEPROP 1 LAST PATH I224
J 0
(-3177 2525);
DISPLAY 0.872340 (-3177 2525);
PAINT GREEN (-3177 2525);
DISPLAY INVISIBLE (-3177 2525);
FORCEADD TAP..1
(-3175 2325);
FORCEPROP 3 LASTPIN (-3225 2325) SIG_NAME M_J_CPU0_SB_DQS_DN<1>
J 0
(-3215 2335);
DISPLAY 0.659574 (-3215 2335);
PAINT MONO (-3215 2335);
DISPLAY INVISIBLE (-3215 2335);
FORCEPROP 1 LASTPIN (-3225 2325) BN 1
J 0
(-3237 2333);
DISPLAY 0.489362 (-3237 2333);
PAINT GREEN (-3237 2333);
FORCEPROP 2 LAST CDS_LIB mstr_standard
J 0
(-3175 2325);
DISPLAY 0.723404 (-3175 2325);
PAINT MONO (-3175 2325);
DISPLAY INVISIBLE (-3175 2325);
FORCEPROP 1 LAST BODY_TYPE PLUMBING
J 0
(-3175 2375);
DISPLAY 0.872340 (-3175 2375);
PAINT GREEN (-3175 2375);
DISPLAY INVISIBLE (-3175 2375);
FORCEPROP 1 LAST HDL_TAP TRUE
J 0
(-2850 2200);
DISPLAY 0.872340 (-2850 2200);
DISPLAY INVISIBLE (-2850 2200);
FORCEPROP 1 LAST PATH I225
J 0
(-3177 2325);
DISPLAY 0.872340 (-3177 2325);
PAINT GREEN (-3177 2325);
DISPLAY INVISIBLE (-3177 2325);
FORCEADD TAP..1
(-3175 2425);
FORCEPROP 3 LASTPIN (-3225 2425) SIG_NAME M_J_CPU0_SB_DQS_DN<2>
J 0
(-3215 2435);
DISPLAY 0.659574 (-3215 2435);
PAINT MONO (-3215 2435);
DISPLAY INVISIBLE (-3215 2435);
FORCEPROP 1 LASTPIN (-3225 2425) BN 2
J 0
(-3237 2433);
DISPLAY 0.489362 (-3237 2433);
PAINT GREEN (-3237 2433);
FORCEPROP 2 LAST CDS_LIB mstr_standard
J 0
(-3175 2425);
DISPLAY 0.723404 (-3175 2425);
PAINT MONO (-3175 2425);
DISPLAY INVISIBLE (-3175 2425);
FORCEPROP 1 LAST BODY_TYPE PLUMBING
J 0
(-3175 2475);
DISPLAY 0.872340 (-3175 2475);
PAINT GREEN (-3175 2475);
DISPLAY INVISIBLE (-3175 2475);
FORCEPROP 1 LAST HDL_TAP TRUE
J 0
(-2850 2300);
DISPLAY 0.872340 (-2850 2300);
DISPLAY INVISIBLE (-2850 2300);
FORCEPROP 1 LAST PATH I226
J 0
(-3177 2425);
DISPLAY 0.872340 (-3177 2425);
PAINT GREEN (-3177 2425);
DISPLAY INVISIBLE (-3177 2425);
FORCEADD TAP..1
(-3175 2225);
FORCEPROP 3 LASTPIN (-3225 2225) SIG_NAME M_J_CPU0_SB_DQS_DN<0>
J 0
(-3215 2235);
DISPLAY 0.659574 (-3215 2235);
PAINT MONO (-3215 2235);
DISPLAY INVISIBLE (-3215 2235);
FORCEPROP 1 LASTPIN (-3225 2225) BN 0
J 0
(-3237 2233);
DISPLAY 0.489362 (-3237 2233);
PAINT GREEN (-3237 2233);
FORCEPROP 2 LAST CDS_LIB mstr_standard
J 0
(-3175 2225);
DISPLAY 0.723404 (-3175 2225);
PAINT MONO (-3175 2225);
DISPLAY INVISIBLE (-3175 2225);
FORCEPROP 1 LAST BODY_TYPE PLUMBING
J 0
(-3175 2275);
DISPLAY 0.872340 (-3175 2275);
PAINT GREEN (-3175 2275);
DISPLAY INVISIBLE (-3175 2275);
FORCEPROP 1 LAST HDL_TAP TRUE
J 0
(-2850 2100);
DISPLAY 0.872340 (-2850 2100);
DISPLAY INVISIBLE (-2850 2100);
FORCEPROP 1 LAST PATH I227
J 0
(-3177 2225);
DISPLAY 0.872340 (-3177 2225);
PAINT GREEN (-3177 2225);
DISPLAY INVISIBLE (-3177 2225);
FORCEADD TAP..1
(-3375 2975);
FORCEPROP 3 LASTPIN (-3425 2975) SIG_NAME M_J_CPU0_SB_DQS_DP<7>
J 0
(-3415 2985);
DISPLAY 0.659574 (-3415 2985);
PAINT MONO (-3415 2985);
DISPLAY INVISIBLE (-3415 2985);
FORCEPROP 1 LASTPIN (-3425 2975) BN 7
J 0
(-3437 2983);
DISPLAY 0.489362 (-3437 2983);
PAINT GREEN (-3437 2983);
FORCEPROP 2 LAST CDS_LIB mstr_standard
J 0
(-3375 2975);
DISPLAY 0.723404 (-3375 2975);
PAINT MONO (-3375 2975);
DISPLAY INVISIBLE (-3375 2975);
FORCEPROP 1 LAST BODY_TYPE PLUMBING
J 0
(-3375 3025);
DISPLAY 0.872340 (-3375 3025);
PAINT GREEN (-3375 3025);
DISPLAY INVISIBLE (-3375 3025);
FORCEPROP 1 LAST HDL_TAP TRUE
J 0
(-3050 2850);
DISPLAY 0.872340 (-3050 2850);
DISPLAY INVISIBLE (-3050 2850);
FORCEPROP 1 LAST PATH I228
J 0
(-3377 2975);
DISPLAY 0.872340 (-3377 2975);
PAINT GREEN (-3377 2975);
DISPLAY INVISIBLE (-3377 2975);
FORCEADD TAP..1
(-3375 2875);
FORCEPROP 3 LASTPIN (-3425 2875) SIG_NAME M_J_CPU0_SB_DQS_DP<6>
J 0
(-3415 2885);
DISPLAY 0.659574 (-3415 2885);
PAINT MONO (-3415 2885);
DISPLAY INVISIBLE (-3415 2885);
FORCEPROP 1 LASTPIN (-3425 2875) BN 6
J 0
(-3437 2883);
DISPLAY 0.489362 (-3437 2883);
PAINT GREEN (-3437 2883);
FORCEPROP 2 LAST CDS_LIB mstr_standard
J 0
(-3375 2875);
DISPLAY 0.723404 (-3375 2875);
PAINT MONO (-3375 2875);
DISPLAY INVISIBLE (-3375 2875);
FORCEPROP 1 LAST BODY_TYPE PLUMBING
J 0
(-3375 2925);
DISPLAY 0.872340 (-3375 2925);
PAINT GREEN (-3375 2925);
DISPLAY INVISIBLE (-3375 2925);
FORCEPROP 1 LAST HDL_TAP TRUE
J 0
(-3050 2750);
DISPLAY 0.872340 (-3050 2750);
DISPLAY INVISIBLE (-3050 2750);
FORCEPROP 1 LAST PATH I229
J 0
(-3377 2875);
DISPLAY 0.872340 (-3377 2875);
PAINT GREEN (-3377 2875);
DISPLAY INVISIBLE (-3377 2875);
FORCEADD TAP..1
R 2
(-7650 3125);
FORCEPROP 3 LASTPIN (-7600 3125) SIG_NAME M_J_CPU0_SB_CB<0>
J 0
(-7590 3135);
DISPLAY 0.659574 (-7590 3135);
PAINT MONO (-7590 3135);
DISPLAY INVISIBLE (-7590 3135);
FORCEPROP 1 LASTPIN (-7600 3125) BN 0
J 2
(-7588 3133);
DISPLAY 0.489362 (-7588 3133);
PAINT GREEN (-7588 3133);
FORCEPROP 2 LAST CDS_LIB mstr_standard
J 0
(-7650 3125);
DISPLAY 0.723404 (-7650 3125);
PAINT MONO (-7650 3125);
DISPLAY INVISIBLE (-7650 3125);
FORCEPROP 1 LAST BODY_TYPE PLUMBING
J 2
(-7650 3175);
DISPLAY 0.872340 (-7650 3175);
PAINT GREEN (-7650 3175);
DISPLAY INVISIBLE (-7650 3175);
FORCEPROP 1 LAST HDL_TAP TRUE
J 2
(-7975 3000);
DISPLAY 0.872340 (-7975 3000);
DISPLAY INVISIBLE (-7975 3000);
FORCEPROP 1 LAST PATH I23
J 2
(-7648 3125);
DISPLAY 0.872340 (-7648 3125);
PAINT GREEN (-7648 3125);
DISPLAY INVISIBLE (-7648 3125);
FORCEADD TAP..1
(-3375 2675);
FORCEPROP 3 LASTPIN (-3425 2675) SIG_NAME M_J_CPU0_SB_DQS_DP<4>
J 0
(-3415 2685);
DISPLAY 0.659574 (-3415 2685);
PAINT MONO (-3415 2685);
DISPLAY INVISIBLE (-3415 2685);
FORCEPROP 1 LASTPIN (-3425 2675) BN 4
J 0
(-3437 2683);
DISPLAY 0.489362 (-3437 2683);
PAINT GREEN (-3437 2683);
FORCEPROP 2 LAST CDS_LIB mstr_standard
J 0
(-3375 2675);
DISPLAY 0.723404 (-3375 2675);
PAINT MONO (-3375 2675);
DISPLAY INVISIBLE (-3375 2675);
FORCEPROP 1 LAST BODY_TYPE PLUMBING
J 0
(-3375 2725);
DISPLAY 0.872340 (-3375 2725);
PAINT GREEN (-3375 2725);
DISPLAY INVISIBLE (-3375 2725);
FORCEPROP 1 LAST HDL_TAP TRUE
J 0
(-3050 2550);
DISPLAY 0.872340 (-3050 2550);
DISPLAY INVISIBLE (-3050 2550);
FORCEPROP 1 LAST PATH I230
J 0
(-3377 2675);
DISPLAY 0.872340 (-3377 2675);
PAINT GREEN (-3377 2675);
DISPLAY INVISIBLE (-3377 2675);
FORCEADD TAP..1
(-3375 2775);
FORCEPROP 3 LASTPIN (-3425 2775) SIG_NAME M_J_CPU0_SB_DQS_DP<5>
J 0
(-3415 2785);
DISPLAY 0.659574 (-3415 2785);
PAINT MONO (-3415 2785);
DISPLAY INVISIBLE (-3415 2785);
FORCEPROP 1 LASTPIN (-3425 2775) BN 5
J 0
(-3437 2783);
DISPLAY 0.489362 (-3437 2783);
PAINT GREEN (-3437 2783);
FORCEPROP 2 LAST CDS_LIB mstr_standard
J 0
(-3375 2775);
DISPLAY 0.723404 (-3375 2775);
PAINT MONO (-3375 2775);
DISPLAY INVISIBLE (-3375 2775);
FORCEPROP 1 LAST BODY_TYPE PLUMBING
J 0
(-3375 2825);
DISPLAY 0.872340 (-3375 2825);
PAINT GREEN (-3375 2825);
DISPLAY INVISIBLE (-3375 2825);
FORCEPROP 1 LAST HDL_TAP TRUE
J 0
(-3050 2650);
DISPLAY 0.872340 (-3050 2650);
DISPLAY INVISIBLE (-3050 2650);
FORCEPROP 1 LAST PATH I231
J 0
(-3377 2775);
DISPLAY 0.872340 (-3377 2775);
PAINT GREEN (-3377 2775);
DISPLAY INVISIBLE (-3377 2775);
FORCEADD TAP..1
(-3375 2575);
FORCEPROP 3 LASTPIN (-3425 2575) SIG_NAME M_J_CPU0_SB_DQS_DP<3>
J 0
(-3415 2585);
DISPLAY 0.659574 (-3415 2585);
PAINT MONO (-3415 2585);
DISPLAY INVISIBLE (-3415 2585);
FORCEPROP 1 LASTPIN (-3425 2575) BN 3
J 0
(-3437 2583);
DISPLAY 0.489362 (-3437 2583);
PAINT GREEN (-3437 2583);
FORCEPROP 2 LAST CDS_LIB mstr_standard
J 0
(-3375 2575);
DISPLAY 0.723404 (-3375 2575);
PAINT MONO (-3375 2575);
DISPLAY INVISIBLE (-3375 2575);
FORCEPROP 1 LAST BODY_TYPE PLUMBING
J 0
(-3375 2625);
DISPLAY 0.872340 (-3375 2625);
PAINT GREEN (-3375 2625);
DISPLAY INVISIBLE (-3375 2625);
FORCEPROP 1 LAST HDL_TAP TRUE
J 0
(-3050 2450);
DISPLAY 0.872340 (-3050 2450);
DISPLAY INVISIBLE (-3050 2450);
FORCEPROP 1 LAST PATH I232
J 0
(-3377 2575);
DISPLAY 0.872340 (-3377 2575);
PAINT GREEN (-3377 2575);
DISPLAY INVISIBLE (-3377 2575);
FORCEADD TAP..1
(-3375 2475);
FORCEPROP 3 LASTPIN (-3425 2475) SIG_NAME M_J_CPU0_SB_DQS_DP<2>
J 0
(-3415 2485);
DISPLAY 0.659574 (-3415 2485);
PAINT MONO (-3415 2485);
DISPLAY INVISIBLE (-3415 2485);
FORCEPROP 1 LASTPIN (-3425 2475) BN 2
J 0
(-3437 2483);
DISPLAY 0.489362 (-3437 2483);
PAINT GREEN (-3437 2483);
FORCEPROP 2 LAST CDS_LIB mstr_standard
J 0
(-3375 2475);
DISPLAY 0.723404 (-3375 2475);
PAINT MONO (-3375 2475);
DISPLAY INVISIBLE (-3375 2475);
FORCEPROP 1 LAST BODY_TYPE PLUMBING
J 0
(-3375 2525);
DISPLAY 0.872340 (-3375 2525);
PAINT GREEN (-3375 2525);
DISPLAY INVISIBLE (-3375 2525);
FORCEPROP 1 LAST HDL_TAP TRUE
J 0
(-3050 2350);
DISPLAY 0.872340 (-3050 2350);
DISPLAY INVISIBLE (-3050 2350);
FORCEPROP 1 LAST PATH I233
J 0
(-3377 2475);
DISPLAY 0.872340 (-3377 2475);
PAINT GREEN (-3377 2475);
DISPLAY INVISIBLE (-3377 2475);
FORCEADD TAP..1
(-3375 2375);
FORCEPROP 3 LASTPIN (-3425 2375) SIG_NAME M_J_CPU0_SB_DQS_DP<1>
J 0
(-3415 2385);
DISPLAY 0.659574 (-3415 2385);
PAINT MONO (-3415 2385);
DISPLAY INVISIBLE (-3415 2385);
FORCEPROP 1 LASTPIN (-3425 2375) BN 1
J 0
(-3437 2383);
DISPLAY 0.489362 (-3437 2383);
PAINT GREEN (-3437 2383);
FORCEPROP 2 LAST CDS_LIB mstr_standard
J 0
(-3375 2375);
DISPLAY 0.723404 (-3375 2375);
PAINT MONO (-3375 2375);
DISPLAY INVISIBLE (-3375 2375);
FORCEPROP 1 LAST BODY_TYPE PLUMBING
J 0
(-3375 2425);
DISPLAY 0.872340 (-3375 2425);
PAINT GREEN (-3375 2425);
DISPLAY INVISIBLE (-3375 2425);
FORCEPROP 1 LAST HDL_TAP TRUE
J 0
(-3050 2250);
DISPLAY 0.872340 (-3050 2250);
DISPLAY INVISIBLE (-3050 2250);
FORCEPROP 1 LAST PATH I234
J 0
(-3377 2375);
DISPLAY 0.872340 (-3377 2375);
PAINT GREEN (-3377 2375);
DISPLAY INVISIBLE (-3377 2375);
FORCEADD TAP..1
(-3375 2275);
FORCEPROP 3 LASTPIN (-3425 2275) SIG_NAME M_J_CPU0_SB_DQS_DP<0>
J 0
(-3415 2285);
DISPLAY 0.659574 (-3415 2285);
PAINT MONO (-3415 2285);
DISPLAY INVISIBLE (-3415 2285);
FORCEPROP 1 LASTPIN (-3425 2275) BN 0
J 0
(-3437 2283);
DISPLAY 0.489362 (-3437 2283);
PAINT GREEN (-3437 2283);
FORCEPROP 2 LAST CDS_LIB mstr_standard
J 0
(-3375 2275);
DISPLAY 0.723404 (-3375 2275);
PAINT MONO (-3375 2275);
DISPLAY INVISIBLE (-3375 2275);
FORCEPROP 1 LAST BODY_TYPE PLUMBING
J 0
(-3375 2325);
DISPLAY 0.872340 (-3375 2325);
PAINT GREEN (-3375 2325);
DISPLAY INVISIBLE (-3375 2325);
FORCEPROP 1 LAST HDL_TAP TRUE
J 0
(-3050 2150);
DISPLAY 0.872340 (-3050 2150);
DISPLAY INVISIBLE (-3050 2150);
FORCEPROP 1 LAST PATH I235
J 0
(-3377 2275);
DISPLAY 0.872340 (-3377 2275);
PAINT GREEN (-3377 2275);
DISPLAY INVISIBLE (-3377 2275);
FORCEADD SCONN288_DDR506112002KQ..2
(-4325 3225);
FORCEPROP 1 LAST LOCATION J68
J 0
(-4925 4550);
DISPLAY 0.468085 (-4925 4550);
PAINT SKYBLUE (-4925 4550);
FORCEPROP 0 LAST $SEC 2
J 0
(-4775 4700);
DISPLAY 0.680851 (-4775 4700);
PAINT MONO (-4775 4700);
DISPLAY INVISIBLE (-4775 4700);
FORCEPROP 0 LAST CDS_SEC 2
J 0
(-4775 4700);
DISPLAY 1.021277 (-4775 4700);
DISPLAY INVISIBLE (-4775 4700);
FORCEPROP 0 LASTPIN (-3575 3275) $PN 12
J 0
(-3565 3285);
DISPLAY 0.680851 (-3565 3285);
PAINT MONO (-3565 3285);
FORCEPROP 0 LASTPIN (-3575 3325) $PN 11
J 0
(-3565 3335);
DISPLAY 0.680851 (-3565 3335);
PAINT MONO (-3565 3335);
FORCEPROP 0 LASTPIN (-3575 2225) $PN 105
J 0
(-3565 2235);
DISPLAY 0.680851 (-3565 2235);
PAINT MONO (-3565 2235);
FORCEPROP 0 LASTPIN (-3575 2275) $PN 104
J 0
(-3565 2285);
DISPLAY 0.680851 (-3565 2285);
PAINT MONO (-3565 2285);
FORCEPROP 0 LASTPIN (-3575 3375) $PN 23
J 0
(-3565 3385);
DISPLAY 0.680851 (-3565 3385);
PAINT MONO (-3565 3385);
FORCEPROP 0 LASTPIN (-3575 3425) $PN 22
J 0
(-3565 3435);
DISPLAY 0.680851 (-3565 3435);
PAINT MONO (-3565 3435);
FORCEPROP 0 LASTPIN (-3575 2325) $PN 116
J 0
(-3565 2335);
DISPLAY 0.680851 (-3565 2335);
PAINT MONO (-3565 2335);
FORCEPROP 0 LASTPIN (-3575 2375) $PN 115
J 0
(-3565 2385);
DISPLAY 0.680851 (-3565 2385);
PAINT MONO (-3565 2385);
FORCEPROP 0 LASTPIN (-3575 3475) $PN 34
J 0
(-3565 3485);
DISPLAY 0.680851 (-3565 3485);
PAINT MONO (-3565 3485);
FORCEPROP 0 LASTPIN (-3575 3525) $PN 33
J 0
(-3565 3535);
DISPLAY 0.680851 (-3565 3535);
PAINT MONO (-3565 3535);
FORCEPROP 0 LASTPIN (-3575 2425) $PN 127
J 0
(-3565 2435);
DISPLAY 0.680851 (-3565 2435);
PAINT MONO (-3565 2435);
FORCEPROP 0 LASTPIN (-3575 2475) $PN 126
J 0
(-3565 2485);
DISPLAY 0.680851 (-3565 2485);
PAINT MONO (-3565 2485);
FORCEPROP 0 LASTPIN (-3575 3575) $PN 45
J 0
(-3565 3585);
DISPLAY 0.680851 (-3565 3585);
PAINT MONO (-3565 3585);
FORCEPROP 0 LASTPIN (-3575 3625) $PN 44
J 0
(-3565 3635);
DISPLAY 0.680851 (-3565 3635);
PAINT MONO (-3565 3635);
FORCEPROP 0 LASTPIN (-3575 2525) $PN 138
J 0
(-3565 2535);
DISPLAY 0.680851 (-3565 2535);
PAINT MONO (-3565 2535);
FORCEPROP 0 LASTPIN (-3575 2575) $PN 137
J 0
(-3565 2585);
DISPLAY 0.680851 (-3565 2585);
PAINT MONO (-3565 2585);
FORCEPROP 0 LASTPIN (-3575 3675) $PN 56
J 0
(-3565 3685);
DISPLAY 0.680851 (-3565 3685);
PAINT MONO (-3565 3685);
FORCEPROP 0 LASTPIN (-3575 3725) $PN 55
J 0
(-3565 3735);
DISPLAY 0.680851 (-3565 3735);
PAINT MONO (-3565 3735);
FORCEPROP 0 LASTPIN (-3575 2625) $PN 238
J 0
(-3565 2635);
DISPLAY 0.680851 (-3565 2635);
PAINT MONO (-3565 2635);
FORCEPROP 0 LASTPIN (-3575 2675) $PN 239
J 0
(-3565 2685);
DISPLAY 0.680851 (-3565 2685);
PAINT MONO (-3565 2685);
FORCEPROP 0 LASTPIN (-3575 3775) $PN 156
J 0
(-3565 3785);
DISPLAY 0.680851 (-3565 3785);
PAINT MONO (-3565 3785);
FORCEPROP 0 LASTPIN (-3575 3825) $PN 157
J 0
(-3565 3835);
DISPLAY 0.680851 (-3565 3835);
PAINT MONO (-3565 3835);
FORCEPROP 0 LASTPIN (-3575 2725) $PN 249
J 0
(-3565 2735);
DISPLAY 0.680851 (-3565 2735);
PAINT MONO (-3565 2735);
FORCEPROP 0 LASTPIN (-3575 2775) $PN 250
J 0
(-3565 2785);
DISPLAY 0.680851 (-3565 2785);
PAINT MONO (-3565 2785);
FORCEPROP 0 LASTPIN (-3575 3875) $PN 167
J 0
(-3565 3885);
DISPLAY 0.680851 (-3565 3885);
PAINT MONO (-3565 3885);
FORCEPROP 0 LASTPIN (-3575 3925) $PN 168
J 0
(-3565 3935);
DISPLAY 0.680851 (-3565 3935);
PAINT MONO (-3565 3935);
FORCEPROP 0 LASTPIN (-3575 2825) $PN 260
J 0
(-3565 2835);
DISPLAY 0.680851 (-3565 2835);
PAINT MONO (-3565 2835);
FORCEPROP 0 LASTPIN (-3575 2875) $PN 261
J 0
(-3565 2885);
DISPLAY 0.680851 (-3565 2885);
PAINT MONO (-3565 2885);
FORCEPROP 0 LASTPIN (-3575 3975) $PN 178
J 0
(-3565 3985);
DISPLAY 0.680851 (-3565 3985);
PAINT MONO (-3565 3985);
FORCEPROP 0 LASTPIN (-3575 4025) $PN 179
J 0
(-3565 4035);
DISPLAY 0.680851 (-3565 4035);
PAINT MONO (-3565 4035);
FORCEPROP 0 LASTPIN (-3575 2925) $PN 271
J 0
(-3565 2935);
DISPLAY 0.680851 (-3565 2935);
PAINT MONO (-3565 2935);
FORCEPROP 0 LASTPIN (-3575 2975) $PN 272
J 0
(-3565 2985);
DISPLAY 0.680851 (-3565 2985);
PAINT MONO (-3565 2985);
FORCEPROP 0 LASTPIN (-3575 4075) $PN 189
J 0
(-3565 4085);
DISPLAY 0.680851 (-3565 4085);
PAINT MONO (-3565 4085);
FORCEPROP 0 LASTPIN (-3575 4125) $PN 190
J 0
(-3565 4135);
DISPLAY 0.680851 (-3565 4135);
PAINT MONO (-3565 4135);
FORCEPROP 0 LASTPIN (-3575 3025) $PN 282
J 0
(-3565 3035);
DISPLAY 0.680851 (-3565 3035);
PAINT MONO (-3565 3035);
FORCEPROP 0 LASTPIN (-3575 3075) $PN 283
J 0
(-3565 3085);
DISPLAY 0.680851 (-3565 3085);
PAINT MONO (-3565 3085);
FORCEPROP 0 LASTPIN (-3575 4175) $PN 200
J 0
(-3565 4185);
DISPLAY 0.680851 (-3565 4185);
PAINT MONO (-3565 4185);
FORCEPROP 0 LASTPIN (-3575 4225) $PN 201
J 0
(-3565 4235);
DISPLAY 0.680851 (-3565 4235);
PAINT MONO (-3565 4235);
FORCEPROP 0 LASTPIN (-3575 3125) $PN 94
J 0
(-3565 3135);
DISPLAY 0.680851 (-3565 3135);
PAINT MONO (-3565 3135);
FORCEPROP 0 LASTPIN (-3575 3175) $PN 93
J 0
(-3565 3185);
DISPLAY 0.680851 (-3565 3185);
PAINT MONO (-3565 3185);
FORCEPROP 1 LAST MATERIAL IO
J 0
(-4925 4400);
DISPLAY 0.468085 (-4925 4400);
PAINT SKYBLUE (-4925 4400);
FORCEPROP 2 LAST VALUE SCONN288_DDR506112002KQ
J 0
(-4775 4600);
DISPLAY 0.489362 (-4775 4600);
PAINT SKYBLUE (-4775 4600);
FORCEPROP 2 LAST PART_TYPE SMLF
J 0
(-4775 4650);
DISPLAY 1.021277 (-4775 4650);
FORCEPROP 1 LAST CDS_LMAN_SYM_OUTLINE -600,1150,600,-1150
J 0
(-4325 3225);
DISPLAY 0.468085 (-4325 3225);
PAINT GREEN (-4325 3225);
DISPLAY INVISIBLE (-4325 3225);
FORCEPROP 1 LAST NEEDS_NO_SIZE TRUE
J 0
(-4325 3225);
DISPLAY 0.723404 (-4325 3225);
PAINT GREEN (-4325 3225);
DISPLAY INVISIBLE (-4325 3225);
FORCEPROP 2 LAST CDS_LIB pure_quanta
J 0
(-4325 3225);
DISPLAY INVISIBLE (-4325 3225);
FORCEPROP 1 LAST PATH I236
J 0
(-4325 3225);
DISPLAY 0.723404 (-4325 3225);
PAINT GREEN (-4325 3225);
DISPLAY INVISIBLE (-4325 3225);
FORCEPROP 1 LAST PART_NUMBER DFHST8FS479
J 0
(-4925 4475);
DISPLAY 0.468085 (-4925 4475);
PAINT SKYBLUE (-4925 4475);
DISPLAY INVISIBLE (-4925 4475);
FORCEADD GND..1
(-2750 5475);
FORCEPROP 3 LASTPIN (-2750 5525) SIG_NAME GND\g
J 0
(-2740 5535);
DISPLAY 0.659574 (-2740 5535);
PAINT MONO (-2740 5535);
DISPLAY INVISIBLE (-2740 5535);
FORCEPROP 2 LAST CDS_LIB pure_quanta_power
J 0
(-2750 5475);
DISPLAY INVISIBLE (-2750 5475);
FORCEPROP 2 LAST BOM_COST MEM
J 0
(-2725 5600);
DISPLAY 0.659574 (-2725 5600);
DISPLAY INVISIBLE (-2725 5600);
FORCEPROP 1 LAST SIZE 1B
J 0
(-2675 5425);
DISPLAY 0.723404 (-2675 5425);
PAINT GREEN (-2675 5425);
DISPLAY INVISIBLE (-2675 5425);
FORCEPROP 2 LAST ROOM MEM_EFGH_DECOUPLING_CAPS
J 0
(-2725 5550);
DISPLAY 0.659574 (-2725 5550);
PAINT RED (-2725 5550);
DISPLAY INVISIBLE (-2725 5550);
FORCEPROP 1 LAST HDL_POWER GND
J 0
(-2750 5625);
DISPLAY 0.723404 (-2750 5625);
PAINT GREEN (-2750 5625);
DISPLAY INVISIBLE (-2750 5625);
FORCEPROP 1 LAST PATH I237
J 0
(-2675 5475);
DISPLAY 0.872340 (-2675 5475);
PAINT AQUA (-2675 5475);
DISPLAY INVISIBLE (-2675 5475);
FORCEADD Q_CAP..1
R 2
(-2750 5825);
FORCEPROP 1 LAST LOCATION C165
J 2
(-2800 5925);
DISPLAY 0.489362 (-2800 5925);
PAINT SKYBLUE (-2800 5925);
FORCEPROP 0 LAST $SEC 1
J 0
(-2800 5975);
DISPLAY 0.680851 (-2800 5975);
PAINT MONO (-2800 5975);
DISPLAY INVISIBLE (-2800 5975);
FORCEPROP 0 LAST CDS_SEC 1
J 0
(-2800 5975);
DISPLAY 0.680851 (-2800 5975);
DISPLAY INVISIBLE (-2800 5975);
FORCEPROP 1 LASTPIN (-2750 5925) $PN 1
J 2
(-2760 5905);
DISPLAY 0.489362 (-2760 5905);
PAINT MONO (-2760 5905);
FORCEPROP 1 LASTPIN (-2750 5725) $PN 2
J 2
(-2760 5705);
DISPLAY 0.489362 (-2760 5705);
PAINT MONO (-2760 5705);
FORCEPROP 1 LAST PACK_TYPE C0805
J 2
(-2800 5625);
DISPLAY 0.489362 (-2800 5625);
PAINT SKYBLUE (-2800 5625);
FORCEPROP 1 LAST VOLTAGE 25V
J 2
(-2800 5825);
DISPLAY 0.489362 (-2800 5825);
PAINT SKYBLUE (-2800 5825);
FORCEPROP 1 LAST VALUE 10UF
J 2
(-2800 5875);
DISPLAY 0.489362 (-2800 5875);
PAINT SKYBLUE (-2800 5875);
FORCEPROP 1 LAST TOLERANCE 10%
J 2
(-2800 5775);
DISPLAY 0.489362 (-2800 5775);
PAINT SKYBLUE (-2800 5775);
FORCEPROP 1 LAST MATERIAL X6S
J 2
(-2800 5725);
DISPLAY 0.489362 (-2800 5725);
PAINT SKYBLUE (-2800 5725);
FORCEPROP 2 LAST CDS_LIB pure_quanta
J 0
(-2750 5825);
DISPLAY INVISIBLE (-2750 5825);
FORCEPROP 0 LAST BOM_COST MEM
J 2
(-2805 5970);
DISPLAY 0.595745 (-2805 5970);
PAINT MONO (-2805 5970);
DISPLAY INVISIBLE (-2805 5970);
FORCEPROP 2 LAST ROOM 
J 2
(-2805 5970);
DISPLAY 0.595745 (-2805 5970);
PAINT RED (-2805 5970);
DISPLAY INVISIBLE (-2805 5970);
FORCEPROP 1 LAST PATH I238
J 2
(-2800 5975);
DISPLAY 0.978723 (-2800 5975);
PAINT WHITE (-2800 5975);
DISPLAY INVISIBLE (-2800 5975);
FORCEPROP 1 LAST PART_NUMBER CH6104KEA00
J 2
(-2800 5675);
DISPLAY 0.489362 (-2800 5675);
PAINT SKYBLUE (-2800 5675);
DISPLAY INVISIBLE (-2800 5675);
FORCEADD Q_CAP..1
R 2
(-2175 5825);
FORCEPROP 1 LAST LOCATION C166
J 2
(-2225 5925);
DISPLAY 0.489362 (-2225 5925);
PAINT SKYBLUE (-2225 5925);
FORCEPROP 0 LAST $SEC 1
J 0
(-2225 5975);
DISPLAY 0.680851 (-2225 5975);
PAINT MONO (-2225 5975);
DISPLAY INVISIBLE (-2225 5975);
FORCEPROP 0 LAST CDS_SEC 1
J 0
(-2225 5975);
DISPLAY 0.680851 (-2225 5975);
DISPLAY INVISIBLE (-2225 5975);
FORCEPROP 1 LASTPIN (-2175 5925) $PN 1
J 2
(-2185 5905);
DISPLAY 0.489362 (-2185 5905);
PAINT MONO (-2185 5905);
FORCEPROP 1 LASTPIN (-2175 5725) $PN 2
J 2
(-2185 5705);
DISPLAY 0.489362 (-2185 5705);
PAINT MONO (-2185 5705);
FORCEPROP 1 LAST VOLTAGE 25V
J 2
(-2225 5825);
DISPLAY 0.489362 (-2225 5825);
PAINT SKYBLUE (-2225 5825);
FORCEPROP 1 LAST PACK_TYPE C0805
J 2
(-2225 5625);
DISPLAY 0.489362 (-2225 5625);
PAINT SKYBLUE (-2225 5625);
FORCEPROP 1 LAST VALUE 10UF
J 2
(-2225 5875);
DISPLAY 0.489362 (-2225 5875);
PAINT SKYBLUE (-2225 5875);
FORCEPROP 1 LAST TOLERANCE 10%
J 2
(-2225 5775);
DISPLAY 0.489362 (-2225 5775);
PAINT SKYBLUE (-2225 5775);
FORCEPROP 1 LAST MATERIAL X6S
J 2
(-2225 5725);
DISPLAY 0.489362 (-2225 5725);
PAINT SKYBLUE (-2225 5725);
FORCEPROP 2 LAST CDS_LIB pure_quanta
J 0
(-2175 5825);
DISPLAY INVISIBLE (-2175 5825);
FORCEPROP 0 LAST BOM_COST MEM
J 2
(-2230 5970);
DISPLAY 0.595745 (-2230 5970);
PAINT MONO (-2230 5970);
DISPLAY INVISIBLE (-2230 5970);
FORCEPROP 2 LAST ROOM 
J 2
(-2230 5970);
DISPLAY 0.595745 (-2230 5970);
PAINT RED (-2230 5970);
DISPLAY INVISIBLE (-2230 5970);
FORCEPROP 1 LAST PATH I239
J 2
(-2225 5975);
DISPLAY 0.978723 (-2225 5975);
PAINT WHITE (-2225 5975);
DISPLAY INVISIBLE (-2225 5975);
FORCEPROP 1 LAST PART_NUMBER CH6104KEA00
J 2
(-2225 5675);
DISPLAY 0.489362 (-2225 5675);
PAINT SKYBLUE (-2225 5675);
DISPLAY INVISIBLE (-2225 5675);
FORCEADD TAP..1
R 2
(-7650 3175);
FORCEPROP 3 LASTPIN (-7600 3175) SIG_NAME M_J_CPU0_SB_CB<1>
J 0
(-7590 3185);
DISPLAY 0.659574 (-7590 3185);
PAINT MONO (-7590 3185);
DISPLAY INVISIBLE (-7590 3185);
FORCEPROP 1 LASTPIN (-7600 3175) BN 1
J 2
(-7588 3183);
DISPLAY 0.489362 (-7588 3183);
PAINT GREEN (-7588 3183);
FORCEPROP 2 LAST CDS_LIB mstr_standard
J 0
(-7650 3175);
DISPLAY 0.723404 (-7650 3175);
PAINT MONO (-7650 3175);
DISPLAY INVISIBLE (-7650 3175);
FORCEPROP 1 LAST BODY_TYPE PLUMBING
J 2
(-7650 3225);
DISPLAY 0.872340 (-7650 3225);
PAINT GREEN (-7650 3225);
DISPLAY INVISIBLE (-7650 3225);
FORCEPROP 1 LAST HDL_TAP TRUE
J 2
(-7975 3050);
DISPLAY 0.872340 (-7975 3050);
DISPLAY INVISIBLE (-7975 3050);
FORCEPROP 1 LAST PATH I24
J 2
(-7648 3175);
DISPLAY 0.872340 (-7648 3175);
PAINT GREEN (-7648 3175);
DISPLAY INVISIBLE (-7648 3175);
FORCEADD UNIVERSAL_POWER..1
(-2750 6150);
FORCEPROP 3 LASTPIN (-2750 6100) SIG_NAME P12V_MEM_CPU0\g
J 0
(-2740 6110);
DISPLAY 0.659574 (-2740 6110);
PAINT MONO (-2740 6110);
DISPLAY INVISIBLE (-2740 6110);
FORCEPROP 1 LAST HDL_POWER P12V_MEM_CPU0
J 1
(-2775 6200);
DISPLAY 0.489362 (-2775 6200);
PAINT GREEN (-2775 6200);
FORCEPROP 2 LAST BOM_COST VR_SYSTEM
J 0
(-2750 6250);
DISPLAY 0.617021 (-2750 6250);
PAINT PURPLE (-2750 6250);
DISPLAY INVISIBLE (-2750 6250);
FORCEPROP 2 LAST CDS_LIB pure_quanta_power
J 0
(-2750 6150);
DISPLAY INVISIBLE (-2750 6150);
FORCEPROP 1 LAST PATH I240
J 0
(-2700 6175);
DISPLAY 0.872340 (-2700 6175);
PAINT AQUA (-2700 6175);
DISPLAY INVISIBLE (-2700 6175);
FORCEADD OFFPAGE..1
(-8300 2550);
FORCEPROP 2 LAST $XR5 97 
J 0
(-9002 2550);
DISPLAY 0.638298 (-9002 2550);
PAINT MONO (-9002 2550);
FORCEPROP 2 LAST $XR4 96 
J 0
(-8912 2550);
DISPLAY 0.638298 (-8912 2550);
PAINT MONO (-8912 2550);
FORCEPROP 2 LAST $XR3 94 
J 0
(-8822 2550);
DISPLAY 0.638298 (-8822 2550);
PAINT MONO (-8822 2550);
FORCEPROP 2 LAST $XR2 93 
J 0
(-8732 2550);
DISPLAY 0.638298 (-8732 2550);
PAINT MONO (-8732 2550);
FORCEPROP 2 LAST $XR1 92 
J 0
(-8642 2550);
DISPLAY 0.638298 (-8642 2550);
PAINT MONO (-8642 2550);
FORCEPROP 2 LAST $XR0 159 
J 0
(-8552 2550);
DISPLAY 0.638298 (-8552 2550);
PAINT MONO (-8552 2550);
FORCEPROP 2 LAST CDS_LIB mstr_standard
J 0
(-8300 2550);
DISPLAY 0.808511 (-8300 2550);
DISPLAY INVISIBLE (-8300 2550);
FORCEPROP 1 LAST OFFPAGE TRUE
J 0
(-7975 2425);
DISPLAY 0.872340 (-7975 2425);
PAINT GREEN (-7975 2425);
DISPLAY INVISIBLE (-7975 2425);
FORCEPROP 1 LAST COMMENT_BODY TRUE
J 0
(-8175 2450);
DISPLAY 0.872340 (-8175 2450);
PAINT GREEN (-8175 2450);
DISPLAY INVISIBLE (-8175 2450);
FORCEPROP 2 LAST PATH I241
J 0
(-8575 2600);
DISPLAY 0.680851 (-8575 2600);
DISPLAY INVISIBLE (-8575 2600);
FORCEADD Q_RES..1
(-7700 2550);
FORCEPROP 1 LAST LOCATION R1577
J 0
(-7750 2575);
DISPLAY 0.510638 (-7750 2575);
PAINT SKYBLUE (-7750 2575);
FORCEPROP 0 LAST $SEC 1
J 0
(-7750 2650);
DISPLAY 0.680851 (-7750 2650);
PAINT MONO (-7750 2650);
DISPLAY INVISIBLE (-7750 2650);
FORCEPROP 0 LAST CDS_SEC 1
J 0
(-7750 2650);
DISPLAY 0.680851 (-7750 2650);
DISPLAY INVISIBLE (-7750 2650);
FORCEPROP 1 LASTPIN (-7800 2550) $PN 1
J 0
(-7788 2562);
DISPLAY 0.787234 (-7788 2562);
PAINT MONO (-7788 2562);
FORCEPROP 1 LASTPIN (-7600 2550) $PN 2
J 0
(-7638 2562);
DISPLAY 0.787234 (-7638 2562);
PAINT MONO (-7638 2562);
FORCEPROP 1 LAST VALUE 49.9
J 2
(-7550 2600);
DISPLAY 0.510638 (-7550 2600);
PAINT SKYBLUE (-7550 2600);
FORCEPROP 1 LAST TOLERANCE 1%
J 0
(-7700 2450);
DISPLAY 0.978723 (-7700 2450);
DISPLAY INVISIBLE (-7700 2450);
FORCEPROP 1 LAST WATTAGE 1/16W
J 2
(-7725 2400);
DISPLAY 0.978723 (-7725 2400);
DISPLAY INVISIBLE (-7725 2400);
FORCEPROP 1 LAST PACK_TYPE 0402LF
J 0
(-7450 2400);
DISPLAY 0.978723 (-7450 2400);
DISPLAY INVISIBLE (-7450 2400);
FORCEPROP 1 LAST MATERIAL CHIP
J 0
(-7700 2400);
DISPLAY 0.978723 (-7700 2400);
DISPLAY INVISIBLE (-7700 2400);
FORCEPROP 2 LAST CDS_LIB pure_quanta
J 0
(-7700 2550);
DISPLAY INVISIBLE (-7700 2550);
FORCEPROP 1 LAST PATH I242
J 0
(-7750 2700);
DISPLAY 0.978723 (-7750 2700);
PAINT WHITE (-7750 2700);
DISPLAY INVISIBLE (-7750 2700);
FORCEPROP 1 LAST PART_NUMBER CS04992FB07
J 0
(-7750 2650);
DISPLAY 0.978723 (-7750 2650);
DISPLAY INVISIBLE (-7750 2650);
FORCEADD Q_RES..1
(-8100 2775);
FORCEPROP 1 LAST LOCATION R1684
J 0
(-8300 2775);
DISPLAY 0.510638 (-8300 2775);
FORCEPROP 0 LAST $SEC 1
J 0
(-8275 2825);
DISPLAY 0.680851 (-8275 2825);
PAINT MONO (-8275 2825);
DISPLAY INVISIBLE (-8275 2825);
FORCEPROP 0 LAST CDS_SEC 1
J 0
(-8275 2825);
DISPLAY 0.680851 (-8275 2825);
DISPLAY INVISIBLE (-8275 2825);
FORCEPROP 1 LASTPIN (-8200 2775) $PN 1
J 0
(-8188 2787);
DISPLAY 0.787234 (-8188 2787);
PAINT MONO (-8188 2787);
FORCEPROP 1 LASTPIN (-8000 2775) $PN 2
J 0
(-8038 2787);
DISPLAY 0.787234 (-8038 2787);
PAINT MONO (-8038 2787);
FORCEPROP 1 LAST VALUE 10
J 2
(-7950 2775);
DISPLAY 0.404255 (-7950 2775);
FORCEPROP 1 LAST PACK_TYPE 0402LF
J 0
(-8050 2750);
DISPLAY 0.404255 (-8050 2750);
FORCEPROP 1 LAST MATERIAL CHIP
J 0
(-8200 2750);
DISPLAY 0.404255 (-8200 2750);
FORCEPROP 2 LAST CDS_LIB pure_quanta
J 0
(-8100 2775);
DISPLAY INVISIBLE (-8100 2775);
FORCEPROP 1 LAST TOLERANCE 1%
J 0
(-8100 2675);
DISPLAY 0.978723 (-8100 2675);
DISPLAY INVISIBLE (-8100 2675);
FORCEPROP 1 LAST WATTAGE 1/16W
J 2
(-8125 2625);
DISPLAY 0.978723 (-8125 2625);
DISPLAY INVISIBLE (-8125 2625);
FORCEPROP 1 LAST PATH I243
J 0
(-8150 2925);
DISPLAY 0.978723 (-8150 2925);
PAINT WHITE (-8150 2925);
DISPLAY INVISIBLE (-8150 2925);
FORCEPROP 1 LAST PART_NUMBER CS01002FB07
J 0
(-8150 2875);
DISPLAY 0.978723 (-8150 2875);
DISPLAY INVISIBLE (-8150 2875);
FORCEADD OFFPAGE..6
(-8800 2650);
FORCEPROP 2 LAST $XR5 159 
J 0
(-9169 2614);
DISPLAY 0.638298 (-9169 2614);
PAINT MONO (-9169 2614);
FORCEPROP 2 LAST $XR4 97 
J 0
(-9049 2614);
DISPLAY 0.638298 (-9049 2614);
PAINT MONO (-9049 2614);
FORCEPROP 2 LAST $XR3 96 
J 0
(-9319 2650);
DISPLAY 0.638298 (-9319 2650);
PAINT MONO (-9319 2650);
FORCEPROP 2 LAST $XR2 94 
J 0
(-9229 2650);
DISPLAY 0.638298 (-9229 2650);
PAINT MONO (-9229 2650);
FORCEPROP 2 LAST $XR1 93 
J 0
(-9139 2650);
DISPLAY 0.638298 (-9139 2650);
PAINT MONO (-9139 2650);
FORCEPROP 2 LAST $XR0 92 
J 0
(-9049 2650);
DISPLAY 0.638298 (-9049 2650);
PAINT MONO (-9049 2650);
FORCEPROP 2 LAST CDS_LIB mstr_standard
J 0
(-8800 2650);
DISPLAY 0.808511 (-8800 2650);
DISPLAY INVISIBLE (-8800 2650);
FORCEPROP 1 LAST OFFPAGE TRUE
J 0
(-8475 2525);
DISPLAY 0.872340 (-8475 2525);
PAINT GREEN (-8475 2525);
DISPLAY INVISIBLE (-8475 2525);
FORCEPROP 1 LAST COMMENT_BODY TRUE
J 0
(-8700 2575);
DISPLAY 0.872340 (-8700 2575);
PAINT GREEN (-8700 2575);
DISPLAY INVISIBLE (-8700 2575);
FORCEPROP 2 LAST PATH I244
J 0
(-9075 2700);
DISPLAY 0.680851 (-9075 2700);
DISPLAY INVISIBLE (-9075 2700);
FORCEADD TAP..1
R 2
(-7650 3225);
FORCEPROP 3 LASTPIN (-7600 3225) SIG_NAME M_J_CPU0_SB_CB<2>
J 0
(-7590 3235);
DISPLAY 0.659574 (-7590 3235);
PAINT MONO (-7590 3235);
DISPLAY INVISIBLE (-7590 3235);
FORCEPROP 1 LASTPIN (-7600 3225) BN 2
J 2
(-7588 3233);
DISPLAY 0.489362 (-7588 3233);
PAINT GREEN (-7588 3233);
FORCEPROP 2 LAST CDS_LIB mstr_standard
J 0
(-7650 3225);
DISPLAY 0.723404 (-7650 3225);
PAINT MONO (-7650 3225);
DISPLAY INVISIBLE (-7650 3225);
FORCEPROP 1 LAST BODY_TYPE PLUMBING
J 2
(-7650 3275);
DISPLAY 0.872340 (-7650 3275);
PAINT GREEN (-7650 3275);
DISPLAY INVISIBLE (-7650 3275);
FORCEPROP 1 LAST HDL_TAP TRUE
J 2
(-7975 3100);
DISPLAY 0.872340 (-7975 3100);
DISPLAY INVISIBLE (-7975 3100);
FORCEPROP 1 LAST PATH I25
J 2
(-7648 3225);
DISPLAY 0.872340 (-7648 3225);
PAINT GREEN (-7648 3225);
DISPLAY INVISIBLE (-7648 3225);
FORCEADD TAP..1
R 2
(-7650 3275);
FORCEPROP 3 LASTPIN (-7600 3275) SIG_NAME M_J_CPU0_SB_CB<3>
J 0
(-7590 3285);
DISPLAY 0.659574 (-7590 3285);
PAINT MONO (-7590 3285);
DISPLAY INVISIBLE (-7590 3285);
FORCEPROP 1 LASTPIN (-7600 3275) BN 3
J 2
(-7588 3283);
DISPLAY 0.489362 (-7588 3283);
PAINT GREEN (-7588 3283);
FORCEPROP 2 LAST CDS_LIB mstr_standard
J 0
(-7650 3275);
DISPLAY 0.723404 (-7650 3275);
PAINT MONO (-7650 3275);
DISPLAY INVISIBLE (-7650 3275);
FORCEPROP 1 LAST BODY_TYPE PLUMBING
J 2
(-7650 3325);
DISPLAY 0.872340 (-7650 3325);
PAINT GREEN (-7650 3325);
DISPLAY INVISIBLE (-7650 3325);
FORCEPROP 1 LAST HDL_TAP TRUE
J 2
(-7975 3150);
DISPLAY 0.872340 (-7975 3150);
DISPLAY INVISIBLE (-7975 3150);
FORCEPROP 1 LAST PATH I26
J 2
(-7648 3275);
DISPLAY 0.872340 (-7648 3275);
PAINT GREEN (-7648 3275);
DISPLAY INVISIBLE (-7648 3275);
FORCEADD TAP..1
R 2
(-7650 3325);
FORCEPROP 3 LASTPIN (-7600 3325) SIG_NAME M_J_CPU0_SB_CB<4>
J 0
(-7590 3335);
DISPLAY 0.659574 (-7590 3335);
PAINT MONO (-7590 3335);
DISPLAY INVISIBLE (-7590 3335);
FORCEPROP 1 LASTPIN (-7600 3325) BN 4
J 2
(-7588 3333);
DISPLAY 0.489362 (-7588 3333);
PAINT GREEN (-7588 3333);
FORCEPROP 2 LAST CDS_LIB mstr_standard
J 0
(-7650 3325);
DISPLAY 0.723404 (-7650 3325);
PAINT MONO (-7650 3325);
DISPLAY INVISIBLE (-7650 3325);
FORCEPROP 1 LAST BODY_TYPE PLUMBING
J 2
(-7650 3375);
DISPLAY 0.872340 (-7650 3375);
PAINT GREEN (-7650 3375);
DISPLAY INVISIBLE (-7650 3375);
FORCEPROP 1 LAST HDL_TAP TRUE
J 2
(-7975 3200);
DISPLAY 0.872340 (-7975 3200);
DISPLAY INVISIBLE (-7975 3200);
FORCEPROP 1 LAST PATH I27
J 2
(-7648 3325);
DISPLAY 0.872340 (-7648 3325);
PAINT GREEN (-7648 3325);
DISPLAY INVISIBLE (-7648 3325);
FORCEADD TAP..1
R 2
(-7650 3375);
FORCEPROP 3 LASTPIN (-7600 3375) SIG_NAME M_J_CPU0_SB_CB<5>
J 0
(-7590 3385);
DISPLAY 0.659574 (-7590 3385);
PAINT MONO (-7590 3385);
DISPLAY INVISIBLE (-7590 3385);
FORCEPROP 1 LASTPIN (-7600 3375) BN 5
J 2
(-7588 3383);
DISPLAY 0.489362 (-7588 3383);
PAINT GREEN (-7588 3383);
FORCEPROP 2 LAST CDS_LIB mstr_standard
J 0
(-7650 3375);
DISPLAY 0.723404 (-7650 3375);
PAINT MONO (-7650 3375);
DISPLAY INVISIBLE (-7650 3375);
FORCEPROP 1 LAST BODY_TYPE PLUMBING
J 2
(-7650 3425);
DISPLAY 0.872340 (-7650 3425);
PAINT GREEN (-7650 3425);
DISPLAY INVISIBLE (-7650 3425);
FORCEPROP 1 LAST HDL_TAP TRUE
J 2
(-7975 3250);
DISPLAY 0.872340 (-7975 3250);
DISPLAY INVISIBLE (-7975 3250);
FORCEPROP 1 LAST PATH I28
J 2
(-7648 3375);
DISPLAY 0.872340 (-7648 3375);
PAINT GREEN (-7648 3375);
DISPLAY INVISIBLE (-7648 3375);
FORCEADD TAP..1
R 2
(-7650 3425);
FORCEPROP 3 LASTPIN (-7600 3425) SIG_NAME M_J_CPU0_SB_CB<6>
J 0
(-7590 3435);
DISPLAY 0.659574 (-7590 3435);
PAINT MONO (-7590 3435);
DISPLAY INVISIBLE (-7590 3435);
FORCEPROP 1 LASTPIN (-7600 3425) BN 6
J 2
(-7588 3433);
DISPLAY 0.489362 (-7588 3433);
PAINT GREEN (-7588 3433);
FORCEPROP 2 LAST CDS_LIB mstr_standard
J 0
(-7650 3425);
DISPLAY 0.723404 (-7650 3425);
PAINT MONO (-7650 3425);
DISPLAY INVISIBLE (-7650 3425);
FORCEPROP 1 LAST BODY_TYPE PLUMBING
J 2
(-7650 3475);
DISPLAY 0.872340 (-7650 3475);
PAINT GREEN (-7650 3475);
DISPLAY INVISIBLE (-7650 3475);
FORCEPROP 1 LAST HDL_TAP TRUE
J 2
(-7975 3300);
DISPLAY 0.872340 (-7975 3300);
DISPLAY INVISIBLE (-7975 3300);
FORCEPROP 1 LAST PATH I29
J 2
(-7648 3425);
DISPLAY 0.872340 (-7648 3425);
PAINT GREEN (-7648 3425);
DISPLAY INVISIBLE (-7648 3425);
FORCEADD TAP..1
R 2
(-7650 3475);
FORCEPROP 3 LASTPIN (-7600 3475) SIG_NAME M_J_CPU0_SB_CB<7>
J 0
(-7590 3485);
DISPLAY 0.659574 (-7590 3485);
PAINT MONO (-7590 3485);
DISPLAY INVISIBLE (-7590 3485);
FORCEPROP 1 LASTPIN (-7600 3475) BN 7
J 2
(-7588 3483);
DISPLAY 0.489362 (-7588 3483);
PAINT GREEN (-7588 3483);
FORCEPROP 2 LAST CDS_LIB mstr_standard
J 0
(-7650 3475);
DISPLAY 0.723404 (-7650 3475);
PAINT MONO (-7650 3475);
DISPLAY INVISIBLE (-7650 3475);
FORCEPROP 1 LAST BODY_TYPE PLUMBING
J 2
(-7650 3525);
DISPLAY 0.872340 (-7650 3525);
PAINT GREEN (-7650 3525);
DISPLAY INVISIBLE (-7650 3525);
FORCEPROP 1 LAST HDL_TAP TRUE
J 2
(-7975 3350);
DISPLAY 0.872340 (-7975 3350);
DISPLAY INVISIBLE (-7975 3350);
FORCEPROP 1 LAST PATH I30
J 2
(-7648 3475);
DISPLAY 0.872340 (-7648 3475);
PAINT GREEN (-7648 3475);
DISPLAY INVISIBLE (-7648 3475);
FORCEADD TAP..1
R 2
(-7650 3575);
FORCEPROP 3 LASTPIN (-7600 3575) SIG_NAME M_J_CPU0_SA_CB<0>
J 0
(-7590 3585);
DISPLAY 0.659574 (-7590 3585);
PAINT MONO (-7590 3585);
DISPLAY INVISIBLE (-7590 3585);
FORCEPROP 1 LASTPIN (-7600 3575) BN 0
J 2
(-7588 3583);
DISPLAY 0.489362 (-7588 3583);
PAINT GREEN (-7588 3583);
FORCEPROP 2 LAST CDS_LIB mstr_standard
J 0
(-7650 3575);
DISPLAY 0.723404 (-7650 3575);
PAINT MONO (-7650 3575);
DISPLAY INVISIBLE (-7650 3575);
FORCEPROP 1 LAST BODY_TYPE PLUMBING
J 2
(-7650 3625);
DISPLAY 0.872340 (-7650 3625);
PAINT GREEN (-7650 3625);
DISPLAY INVISIBLE (-7650 3625);
FORCEPROP 1 LAST HDL_TAP TRUE
J 2
(-7975 3450);
DISPLAY 0.872340 (-7975 3450);
DISPLAY INVISIBLE (-7975 3450);
FORCEPROP 1 LAST PATH I31
J 2
(-7648 3575);
DISPLAY 0.872340 (-7648 3575);
PAINT GREEN (-7648 3575);
DISPLAY INVISIBLE (-7648 3575);
FORCEADD TAP..1
R 2
(-7650 3625);
FORCEPROP 3 LASTPIN (-7600 3625) SIG_NAME M_J_CPU0_SA_CB<1>
J 0
(-7590 3635);
DISPLAY 0.659574 (-7590 3635);
PAINT MONO (-7590 3635);
DISPLAY INVISIBLE (-7590 3635);
FORCEPROP 1 LASTPIN (-7600 3625) BN 1
J 2
(-7588 3633);
DISPLAY 0.489362 (-7588 3633);
PAINT GREEN (-7588 3633);
FORCEPROP 2 LAST CDS_LIB mstr_standard
J 0
(-7650 3625);
DISPLAY 0.723404 (-7650 3625);
PAINT MONO (-7650 3625);
DISPLAY INVISIBLE (-7650 3625);
FORCEPROP 1 LAST BODY_TYPE PLUMBING
J 2
(-7650 3675);
DISPLAY 0.872340 (-7650 3675);
PAINT GREEN (-7650 3675);
DISPLAY INVISIBLE (-7650 3675);
FORCEPROP 1 LAST HDL_TAP TRUE
J 2
(-7975 3500);
DISPLAY 0.872340 (-7975 3500);
DISPLAY INVISIBLE (-7975 3500);
FORCEPROP 1 LAST PATH I32
J 2
(-7648 3625);
DISPLAY 0.872340 (-7648 3625);
PAINT GREEN (-7648 3625);
DISPLAY INVISIBLE (-7648 3625);
FORCEADD TAP..1
R 2
(-7650 3725);
FORCEPROP 3 LASTPIN (-7600 3725) SIG_NAME M_J_CPU0_SA_CB<3>
J 0
(-7590 3735);
DISPLAY 0.659574 (-7590 3735);
PAINT MONO (-7590 3735);
DISPLAY INVISIBLE (-7590 3735);
FORCEPROP 1 LASTPIN (-7600 3725) BN 3
J 2
(-7588 3733);
DISPLAY 0.489362 (-7588 3733);
PAINT GREEN (-7588 3733);
FORCEPROP 2 LAST CDS_LIB mstr_standard
J 0
(-7650 3725);
DISPLAY 0.723404 (-7650 3725);
PAINT MONO (-7650 3725);
DISPLAY INVISIBLE (-7650 3725);
FORCEPROP 1 LAST BODY_TYPE PLUMBING
J 2
(-7650 3775);
DISPLAY 0.872340 (-7650 3775);
PAINT GREEN (-7650 3775);
DISPLAY INVISIBLE (-7650 3775);
FORCEPROP 1 LAST HDL_TAP TRUE
J 2
(-7975 3600);
DISPLAY 0.872340 (-7975 3600);
DISPLAY INVISIBLE (-7975 3600);
FORCEPROP 1 LAST PATH I33
J 2
(-7648 3725);
DISPLAY 0.872340 (-7648 3725);
PAINT GREEN (-7648 3725);
DISPLAY INVISIBLE (-7648 3725);
FORCEADD TAP..1
R 2
(-7650 3675);
FORCEPROP 3 LASTPIN (-7600 3675) SIG_NAME M_J_CPU0_SA_CB<2>
J 0
(-7590 3685);
DISPLAY 0.659574 (-7590 3685);
PAINT MONO (-7590 3685);
DISPLAY INVISIBLE (-7590 3685);
FORCEPROP 1 LASTPIN (-7600 3675) BN 2
J 2
(-7588 3683);
DISPLAY 0.489362 (-7588 3683);
PAINT GREEN (-7588 3683);
FORCEPROP 2 LAST CDS_LIB mstr_standard
J 0
(-7650 3675);
DISPLAY 0.723404 (-7650 3675);
PAINT MONO (-7650 3675);
DISPLAY INVISIBLE (-7650 3675);
FORCEPROP 1 LAST BODY_TYPE PLUMBING
J 2
(-7650 3725);
DISPLAY 0.872340 (-7650 3725);
PAINT GREEN (-7650 3725);
DISPLAY INVISIBLE (-7650 3725);
FORCEPROP 1 LAST HDL_TAP TRUE
J 2
(-7975 3550);
DISPLAY 0.872340 (-7975 3550);
DISPLAY INVISIBLE (-7975 3550);
FORCEPROP 1 LAST PATH I34
J 2
(-7648 3675);
DISPLAY 0.872340 (-7648 3675);
PAINT GREEN (-7648 3675);
DISPLAY INVISIBLE (-7648 3675);
FORCEADD TAP..1
(-5950 2125);
FORCEPROP 3 LASTPIN (-6000 2125) SIG_NAME M_J_CPU0_SB_DQ<0>
J 0
(-5990 2135);
DISPLAY 0.659574 (-5990 2135);
PAINT MONO (-5990 2135);
DISPLAY INVISIBLE (-5990 2135);
FORCEPROP 1 LASTPIN (-6000 2125) BN 0
J 0
(-6012 2133);
DISPLAY 0.489362 (-6012 2133);
PAINT GREEN (-6012 2133);
FORCEPROP 2 LAST CDS_LIB mstr_standard
J 0
(-5950 2125);
DISPLAY 0.723404 (-5950 2125);
PAINT MONO (-5950 2125);
DISPLAY INVISIBLE (-5950 2125);
FORCEPROP 1 LAST BODY_TYPE PLUMBING
J 0
(-5950 2175);
DISPLAY 0.872340 (-5950 2175);
PAINT GREEN (-5950 2175);
DISPLAY INVISIBLE (-5950 2175);
FORCEPROP 1 LAST HDL_TAP TRUE
J 0
(-5625 2000);
DISPLAY 0.872340 (-5625 2000);
DISPLAY INVISIBLE (-5625 2000);
FORCEPROP 1 LAST PATH I35
J 0
(-5952 2125);
DISPLAY 0.872340 (-5952 2125);
PAINT GREEN (-5952 2125);
DISPLAY INVISIBLE (-5952 2125);
FORCEADD TAP..1
(-5950 2225);
FORCEPROP 3 LASTPIN (-6000 2225) SIG_NAME M_J_CPU0_SB_DQ<2>
J 0
(-5990 2235);
DISPLAY 0.659574 (-5990 2235);
PAINT MONO (-5990 2235);
DISPLAY INVISIBLE (-5990 2235);
FORCEPROP 1 LASTPIN (-6000 2225) BN 2
J 0
(-6012 2233);
DISPLAY 0.489362 (-6012 2233);
PAINT GREEN (-6012 2233);
FORCEPROP 2 LAST CDS_LIB mstr_standard
J 0
(-5950 2225);
DISPLAY 0.723404 (-5950 2225);
PAINT MONO (-5950 2225);
DISPLAY INVISIBLE (-5950 2225);
FORCEPROP 1 LAST BODY_TYPE PLUMBING
J 0
(-5950 2275);
DISPLAY 0.872340 (-5950 2275);
PAINT GREEN (-5950 2275);
DISPLAY INVISIBLE (-5950 2275);
FORCEPROP 1 LAST HDL_TAP TRUE
J 0
(-5625 2100);
DISPLAY 0.872340 (-5625 2100);
DISPLAY INVISIBLE (-5625 2100);
FORCEPROP 1 LAST PATH I36
J 0
(-5952 2225);
DISPLAY 0.872340 (-5952 2225);
PAINT GREEN (-5952 2225);
DISPLAY INVISIBLE (-5952 2225);
FORCEADD TAP..1
(-5950 2175);
FORCEPROP 3 LASTPIN (-6000 2175) SIG_NAME M_J_CPU0_SB_DQ<1>
J 0
(-5990 2185);
DISPLAY 0.659574 (-5990 2185);
PAINT MONO (-5990 2185);
DISPLAY INVISIBLE (-5990 2185);
FORCEPROP 1 LASTPIN (-6000 2175) BN 1
J 0
(-6012 2183);
DISPLAY 0.489362 (-6012 2183);
PAINT GREEN (-6012 2183);
FORCEPROP 2 LAST CDS_LIB mstr_standard
J 0
(-5950 2175);
DISPLAY 0.723404 (-5950 2175);
PAINT MONO (-5950 2175);
DISPLAY INVISIBLE (-5950 2175);
FORCEPROP 1 LAST BODY_TYPE PLUMBING
J 0
(-5950 2225);
DISPLAY 0.872340 (-5950 2225);
PAINT GREEN (-5950 2225);
DISPLAY INVISIBLE (-5950 2225);
FORCEPROP 1 LAST HDL_TAP TRUE
J 0
(-5625 2050);
DISPLAY 0.872340 (-5625 2050);
DISPLAY INVISIBLE (-5625 2050);
FORCEPROP 1 LAST PATH I37
J 0
(-5952 2175);
DISPLAY 0.872340 (-5952 2175);
PAINT GREEN (-5952 2175);
DISPLAY INVISIBLE (-5952 2175);
FORCEADD TAP..1
(-5950 2325);
FORCEPROP 3 LASTPIN (-6000 2325) SIG_NAME M_J_CPU0_SB_DQ<4>
J 0
(-5990 2335);
DISPLAY 0.659574 (-5990 2335);
PAINT MONO (-5990 2335);
DISPLAY INVISIBLE (-5990 2335);
FORCEPROP 1 LASTPIN (-6000 2325) BN 4
J 0
(-6012 2333);
DISPLAY 0.489362 (-6012 2333);
PAINT GREEN (-6012 2333);
FORCEPROP 2 LAST CDS_LIB mstr_standard
J 0
(-5950 2325);
DISPLAY 0.723404 (-5950 2325);
PAINT MONO (-5950 2325);
DISPLAY INVISIBLE (-5950 2325);
FORCEPROP 1 LAST BODY_TYPE PLUMBING
J 0
(-5950 2375);
DISPLAY 0.872340 (-5950 2375);
PAINT GREEN (-5950 2375);
DISPLAY INVISIBLE (-5950 2375);
FORCEPROP 1 LAST HDL_TAP TRUE
J 0
(-5625 2200);
DISPLAY 0.872340 (-5625 2200);
DISPLAY INVISIBLE (-5625 2200);
FORCEPROP 1 LAST PATH I38
J 0
(-5952 2325);
DISPLAY 0.872340 (-5952 2325);
PAINT GREEN (-5952 2325);
DISPLAY INVISIBLE (-5952 2325);
FORCEADD TAP..1
(-5950 2275);
FORCEPROP 3 LASTPIN (-6000 2275) SIG_NAME M_J_CPU0_SB_DQ<3>
J 0
(-5990 2285);
DISPLAY 0.659574 (-5990 2285);
PAINT MONO (-5990 2285);
DISPLAY INVISIBLE (-5990 2285);
FORCEPROP 1 LASTPIN (-6000 2275) BN 3
J 0
(-6012 2283);
DISPLAY 0.489362 (-6012 2283);
PAINT GREEN (-6012 2283);
FORCEPROP 2 LAST CDS_LIB mstr_standard
J 0
(-5950 2275);
DISPLAY 0.723404 (-5950 2275);
PAINT MONO (-5950 2275);
DISPLAY INVISIBLE (-5950 2275);
FORCEPROP 1 LAST BODY_TYPE PLUMBING
J 0
(-5950 2325);
DISPLAY 0.872340 (-5950 2325);
PAINT GREEN (-5950 2325);
DISPLAY INVISIBLE (-5950 2325);
FORCEPROP 1 LAST HDL_TAP TRUE
J 0
(-5625 2150);
DISPLAY 0.872340 (-5625 2150);
DISPLAY INVISIBLE (-5625 2150);
FORCEPROP 1 LAST PATH I39
J 0
(-5952 2275);
DISPLAY 0.872340 (-5952 2275);
PAINT GREEN (-5952 2275);
DISPLAY INVISIBLE (-5952 2275);
FORCEADD TAP..1
(-5950 2375);
FORCEPROP 3 LASTPIN (-6000 2375) SIG_NAME M_J_CPU0_SB_DQ<5>
J 0
(-5990 2385);
DISPLAY 0.659574 (-5990 2385);
PAINT MONO (-5990 2385);
DISPLAY INVISIBLE (-5990 2385);
FORCEPROP 1 LASTPIN (-6000 2375) BN 5
J 0
(-6012 2383);
DISPLAY 0.489362 (-6012 2383);
PAINT GREEN (-6012 2383);
FORCEPROP 2 LAST CDS_LIB mstr_standard
J 0
(-5950 2375);
DISPLAY 0.723404 (-5950 2375);
PAINT MONO (-5950 2375);
DISPLAY INVISIBLE (-5950 2375);
FORCEPROP 1 LAST BODY_TYPE PLUMBING
J 0
(-5950 2425);
DISPLAY 0.872340 (-5950 2425);
PAINT GREEN (-5950 2425);
DISPLAY INVISIBLE (-5950 2425);
FORCEPROP 1 LAST HDL_TAP TRUE
J 0
(-5625 2250);
DISPLAY 0.872340 (-5625 2250);
DISPLAY INVISIBLE (-5625 2250);
FORCEPROP 1 LAST PATH I40
J 0
(-5952 2375);
DISPLAY 0.872340 (-5952 2375);
PAINT GREEN (-5952 2375);
DISPLAY INVISIBLE (-5952 2375);
FORCEADD TAP..1
(-5950 2425);
FORCEPROP 3 LASTPIN (-6000 2425) SIG_NAME M_J_CPU0_SB_DQ<6>
J 0
(-5990 2435);
DISPLAY 0.659574 (-5990 2435);
PAINT MONO (-5990 2435);
DISPLAY INVISIBLE (-5990 2435);
FORCEPROP 1 LASTPIN (-6000 2425) BN 6
J 0
(-6012 2433);
DISPLAY 0.489362 (-6012 2433);
PAINT GREEN (-6012 2433);
FORCEPROP 2 LAST CDS_LIB mstr_standard
J 0
(-5950 2425);
DISPLAY 0.723404 (-5950 2425);
PAINT MONO (-5950 2425);
DISPLAY INVISIBLE (-5950 2425);
FORCEPROP 1 LAST BODY_TYPE PLUMBING
J 0
(-5950 2475);
DISPLAY 0.872340 (-5950 2475);
PAINT GREEN (-5950 2475);
DISPLAY INVISIBLE (-5950 2475);
FORCEPROP 1 LAST HDL_TAP TRUE
J 0
(-5625 2300);
DISPLAY 0.872340 (-5625 2300);
DISPLAY INVISIBLE (-5625 2300);
FORCEPROP 1 LAST PATH I41
J 0
(-5952 2425);
DISPLAY 0.872340 (-5952 2425);
PAINT GREEN (-5952 2425);
DISPLAY INVISIBLE (-5952 2425);
FORCEADD TAP..1
(-5950 2475);
FORCEPROP 3 LASTPIN (-6000 2475) SIG_NAME M_J_CPU0_SB_DQ<7>
J 0
(-5990 2485);
DISPLAY 0.659574 (-5990 2485);
PAINT MONO (-5990 2485);
DISPLAY INVISIBLE (-5990 2485);
FORCEPROP 1 LASTPIN (-6000 2475) BN 7
J 0
(-6012 2483);
DISPLAY 0.489362 (-6012 2483);
PAINT GREEN (-6012 2483);
FORCEPROP 2 LAST CDS_LIB mstr_standard
J 0
(-5950 2475);
DISPLAY 0.723404 (-5950 2475);
PAINT MONO (-5950 2475);
DISPLAY INVISIBLE (-5950 2475);
FORCEPROP 1 LAST BODY_TYPE PLUMBING
J 0
(-5950 2525);
DISPLAY 0.872340 (-5950 2525);
PAINT GREEN (-5950 2525);
DISPLAY INVISIBLE (-5950 2525);
FORCEPROP 1 LAST HDL_TAP TRUE
J 0
(-5625 2350);
DISPLAY 0.872340 (-5625 2350);
DISPLAY INVISIBLE (-5625 2350);
FORCEPROP 1 LAST PATH I42
J 0
(-5952 2475);
DISPLAY 0.872340 (-5952 2475);
PAINT GREEN (-5952 2475);
DISPLAY INVISIBLE (-5952 2475);
FORCEADD TAP..1
(-5950 2575);
FORCEPROP 3 LASTPIN (-6000 2575) SIG_NAME M_J_CPU0_SB_DQ<9>
J 0
(-5990 2585);
DISPLAY 0.659574 (-5990 2585);
PAINT MONO (-5990 2585);
DISPLAY INVISIBLE (-5990 2585);
FORCEPROP 1 LASTPIN (-6000 2575) BN 9
J 0
(-6012 2583);
DISPLAY 0.489362 (-6012 2583);
PAINT GREEN (-6012 2583);
FORCEPROP 2 LAST CDS_LIB mstr_standard
J 0
(-5950 2575);
DISPLAY 0.723404 (-5950 2575);
PAINT MONO (-5950 2575);
DISPLAY INVISIBLE (-5950 2575);
FORCEPROP 1 LAST BODY_TYPE PLUMBING
J 0
(-5950 2625);
DISPLAY 0.872340 (-5950 2625);
PAINT GREEN (-5950 2625);
DISPLAY INVISIBLE (-5950 2625);
FORCEPROP 1 LAST HDL_TAP TRUE
J 0
(-5625 2450);
DISPLAY 0.872340 (-5625 2450);
DISPLAY INVISIBLE (-5625 2450);
FORCEPROP 1 LAST PATH I43
J 0
(-5952 2575);
DISPLAY 0.872340 (-5952 2575);
PAINT GREEN (-5952 2575);
DISPLAY INVISIBLE (-5952 2575);
FORCEADD TAP..1
(-5950 2525);
FORCEPROP 3 LASTPIN (-6000 2525) SIG_NAME M_J_CPU0_SB_DQ<8>
J 0
(-5990 2535);
DISPLAY 0.659574 (-5990 2535);
PAINT MONO (-5990 2535);
DISPLAY INVISIBLE (-5990 2535);
FORCEPROP 1 LASTPIN (-6000 2525) BN 8
J 0
(-6012 2533);
DISPLAY 0.489362 (-6012 2533);
PAINT GREEN (-6012 2533);
FORCEPROP 2 LAST CDS_LIB mstr_standard
J 0
(-5950 2525);
DISPLAY 0.723404 (-5950 2525);
PAINT MONO (-5950 2525);
DISPLAY INVISIBLE (-5950 2525);
FORCEPROP 1 LAST BODY_TYPE PLUMBING
J 0
(-5950 2575);
DISPLAY 0.872340 (-5950 2575);
PAINT GREEN (-5950 2575);
DISPLAY INVISIBLE (-5950 2575);
FORCEPROP 1 LAST HDL_TAP TRUE
J 0
(-5625 2400);
DISPLAY 0.872340 (-5625 2400);
DISPLAY INVISIBLE (-5625 2400);
FORCEPROP 1 LAST PATH I44
J 0
(-5952 2525);
DISPLAY 0.872340 (-5952 2525);
PAINT GREEN (-5952 2525);
DISPLAY INVISIBLE (-5952 2525);
FORCEADD TAP..1
(-5950 2625);
FORCEPROP 3 LASTPIN (-6000 2625) SIG_NAME M_J_CPU0_SB_DQ<10>
J 0
(-5990 2635);
DISPLAY 0.659574 (-5990 2635);
PAINT MONO (-5990 2635);
DISPLAY INVISIBLE (-5990 2635);
FORCEPROP 1 LASTPIN (-6000 2625) BN 10
J 0
(-6012 2633);
DISPLAY 0.489362 (-6012 2633);
PAINT GREEN (-6012 2633);
FORCEPROP 2 LAST CDS_LIB mstr_standard
J 0
(-5950 2625);
DISPLAY 0.723404 (-5950 2625);
PAINT MONO (-5950 2625);
DISPLAY INVISIBLE (-5950 2625);
FORCEPROP 1 LAST BODY_TYPE PLUMBING
J 0
(-5950 2675);
DISPLAY 0.872340 (-5950 2675);
PAINT GREEN (-5950 2675);
DISPLAY INVISIBLE (-5950 2675);
FORCEPROP 1 LAST HDL_TAP TRUE
J 0
(-5625 2500);
DISPLAY 0.872340 (-5625 2500);
DISPLAY INVISIBLE (-5625 2500);
FORCEPROP 1 LAST PATH I45
J 0
(-5952 2625);
DISPLAY 0.872340 (-5952 2625);
PAINT GREEN (-5952 2625);
DISPLAY INVISIBLE (-5952 2625);
FORCEADD TAP..1
(-5950 2725);
FORCEPROP 3 LASTPIN (-6000 2725) SIG_NAME M_J_CPU0_SB_DQ<12>
J 0
(-5990 2735);
DISPLAY 0.659574 (-5990 2735);
PAINT MONO (-5990 2735);
DISPLAY INVISIBLE (-5990 2735);
FORCEPROP 1 LASTPIN (-6000 2725) BN 12
J 0
(-6012 2733);
DISPLAY 0.489362 (-6012 2733);
PAINT GREEN (-6012 2733);
FORCEPROP 2 LAST CDS_LIB mstr_standard
J 0
(-5950 2725);
DISPLAY 0.723404 (-5950 2725);
PAINT MONO (-5950 2725);
DISPLAY INVISIBLE (-5950 2725);
FORCEPROP 1 LAST BODY_TYPE PLUMBING
J 0
(-5950 2775);
DISPLAY 0.872340 (-5950 2775);
PAINT GREEN (-5950 2775);
DISPLAY INVISIBLE (-5950 2775);
FORCEPROP 1 LAST HDL_TAP TRUE
J 0
(-5625 2600);
DISPLAY 0.872340 (-5625 2600);
DISPLAY INVISIBLE (-5625 2600);
FORCEPROP 1 LAST PATH I46
J 0
(-5952 2725);
DISPLAY 0.872340 (-5952 2725);
PAINT GREEN (-5952 2725);
DISPLAY INVISIBLE (-5952 2725);
FORCEADD TAP..1
(-5950 2675);
FORCEPROP 3 LASTPIN (-6000 2675) SIG_NAME M_J_CPU0_SB_DQ<11>
J 0
(-5990 2685);
DISPLAY 0.659574 (-5990 2685);
PAINT MONO (-5990 2685);
DISPLAY INVISIBLE (-5990 2685);
FORCEPROP 1 LASTPIN (-6000 2675) BN 11
J 0
(-6012 2683);
DISPLAY 0.489362 (-6012 2683);
PAINT GREEN (-6012 2683);
FORCEPROP 2 LAST CDS_LIB mstr_standard
J 0
(-5950 2675);
DISPLAY 0.723404 (-5950 2675);
PAINT MONO (-5950 2675);
DISPLAY INVISIBLE (-5950 2675);
FORCEPROP 1 LAST BODY_TYPE PLUMBING
J 0
(-5950 2725);
DISPLAY 0.872340 (-5950 2725);
PAINT GREEN (-5950 2725);
DISPLAY INVISIBLE (-5950 2725);
FORCEPROP 1 LAST HDL_TAP TRUE
J 0
(-5625 2550);
DISPLAY 0.872340 (-5625 2550);
DISPLAY INVISIBLE (-5625 2550);
FORCEPROP 1 LAST PATH I47
J 0
(-5952 2675);
DISPLAY 0.872340 (-5952 2675);
PAINT GREEN (-5952 2675);
DISPLAY INVISIBLE (-5952 2675);
FORCEADD TAP..1
(-5950 2825);
FORCEPROP 3 LASTPIN (-6000 2825) SIG_NAME M_J_CPU0_SB_DQ<14>
J 0
(-5990 2835);
DISPLAY 0.659574 (-5990 2835);
PAINT MONO (-5990 2835);
DISPLAY INVISIBLE (-5990 2835);
FORCEPROP 1 LASTPIN (-6000 2825) BN 14
J 0
(-6012 2833);
DISPLAY 0.489362 (-6012 2833);
PAINT GREEN (-6012 2833);
FORCEPROP 2 LAST CDS_LIB mstr_standard
J 0
(-5950 2825);
DISPLAY 0.723404 (-5950 2825);
PAINT MONO (-5950 2825);
DISPLAY INVISIBLE (-5950 2825);
FORCEPROP 1 LAST BODY_TYPE PLUMBING
J 0
(-5950 2875);
DISPLAY 0.872340 (-5950 2875);
PAINT GREEN (-5950 2875);
DISPLAY INVISIBLE (-5950 2875);
FORCEPROP 1 LAST HDL_TAP TRUE
J 0
(-5625 2700);
DISPLAY 0.872340 (-5625 2700);
DISPLAY INVISIBLE (-5625 2700);
FORCEPROP 1 LAST PATH I48
J 0
(-5952 2825);
DISPLAY 0.872340 (-5952 2825);
PAINT GREEN (-5952 2825);
DISPLAY INVISIBLE (-5952 2825);
FORCEADD TAP..1
(-5950 2775);
FORCEPROP 3 LASTPIN (-6000 2775) SIG_NAME M_J_CPU0_SB_DQ<13>
J 0
(-5990 2785);
DISPLAY 0.659574 (-5990 2785);
PAINT MONO (-5990 2785);
DISPLAY INVISIBLE (-5990 2785);
FORCEPROP 1 LASTPIN (-6000 2775) BN 13
J 0
(-6012 2783);
DISPLAY 0.489362 (-6012 2783);
PAINT GREEN (-6012 2783);
FORCEPROP 2 LAST CDS_LIB mstr_standard
J 0
(-5950 2775);
DISPLAY 0.723404 (-5950 2775);
PAINT MONO (-5950 2775);
DISPLAY INVISIBLE (-5950 2775);
FORCEPROP 1 LAST BODY_TYPE PLUMBING
J 0
(-5950 2825);
DISPLAY 0.872340 (-5950 2825);
PAINT GREEN (-5950 2825);
DISPLAY INVISIBLE (-5950 2825);
FORCEPROP 1 LAST HDL_TAP TRUE
J 0
(-5625 2650);
DISPLAY 0.872340 (-5625 2650);
DISPLAY INVISIBLE (-5625 2650);
FORCEPROP 1 LAST PATH I49
J 0
(-5952 2775);
DISPLAY 0.872340 (-5952 2775);
PAINT GREEN (-5952 2775);
DISPLAY INVISIBLE (-5952 2775);
FORCEADD TAP..1
(-5950 2875);
FORCEPROP 3 LASTPIN (-6000 2875) SIG_NAME M_J_CPU0_SB_DQ<15>
J 0
(-5990 2885);
DISPLAY 0.659574 (-5990 2885);
PAINT MONO (-5990 2885);
DISPLAY INVISIBLE (-5990 2885);
FORCEPROP 1 LASTPIN (-6000 2875) BN 15
J 0
(-6012 2883);
DISPLAY 0.489362 (-6012 2883);
PAINT GREEN (-6012 2883);
FORCEPROP 2 LAST CDS_LIB mstr_standard
J 0
(-5950 2875);
DISPLAY 0.723404 (-5950 2875);
PAINT MONO (-5950 2875);
DISPLAY INVISIBLE (-5950 2875);
FORCEPROP 1 LAST BODY_TYPE PLUMBING
J 0
(-5950 2925);
DISPLAY 0.872340 (-5950 2925);
PAINT GREEN (-5950 2925);
DISPLAY INVISIBLE (-5950 2925);
FORCEPROP 1 LAST HDL_TAP TRUE
J 0
(-5625 2750);
DISPLAY 0.872340 (-5625 2750);
DISPLAY INVISIBLE (-5625 2750);
FORCEPROP 1 LAST PATH I50
J 0
(-5952 2875);
DISPLAY 0.872340 (-5952 2875);
PAINT GREEN (-5952 2875);
DISPLAY INVISIBLE (-5952 2875);
FORCEADD TAP..1
(-5950 2975);
FORCEPROP 3 LASTPIN (-6000 2975) SIG_NAME M_J_CPU0_SB_DQ<17>
J 0
(-5990 2985);
DISPLAY 0.659574 (-5990 2985);
PAINT MONO (-5990 2985);
DISPLAY INVISIBLE (-5990 2985);
FORCEPROP 1 LASTPIN (-6000 2975) BN 17
J 0
(-6012 2983);
DISPLAY 0.489362 (-6012 2983);
PAINT GREEN (-6012 2983);
FORCEPROP 2 LAST CDS_LIB mstr_standard
J 0
(-5950 2975);
DISPLAY 0.723404 (-5950 2975);
PAINT MONO (-5950 2975);
DISPLAY INVISIBLE (-5950 2975);
FORCEPROP 1 LAST BODY_TYPE PLUMBING
J 0
(-5950 3025);
DISPLAY 0.872340 (-5950 3025);
PAINT GREEN (-5950 3025);
DISPLAY INVISIBLE (-5950 3025);
FORCEPROP 1 LAST HDL_TAP TRUE
J 0
(-5625 2850);
DISPLAY 0.872340 (-5625 2850);
DISPLAY INVISIBLE (-5625 2850);
FORCEPROP 1 LAST PATH I51
J 0
(-5952 2975);
DISPLAY 0.872340 (-5952 2975);
PAINT GREEN (-5952 2975);
DISPLAY INVISIBLE (-5952 2975);
FORCEADD TAP..1
(-5950 2925);
FORCEPROP 3 LASTPIN (-6000 2925) SIG_NAME M_J_CPU0_SB_DQ<16>
J 0
(-5990 2935);
DISPLAY 0.659574 (-5990 2935);
PAINT MONO (-5990 2935);
DISPLAY INVISIBLE (-5990 2935);
FORCEPROP 1 LASTPIN (-6000 2925) BN 16
J 0
(-6012 2933);
DISPLAY 0.489362 (-6012 2933);
PAINT GREEN (-6012 2933);
FORCEPROP 2 LAST CDS_LIB mstr_standard
J 0
(-5950 2925);
DISPLAY 0.723404 (-5950 2925);
PAINT MONO (-5950 2925);
DISPLAY INVISIBLE (-5950 2925);
FORCEPROP 1 LAST BODY_TYPE PLUMBING
J 0
(-5950 2975);
DISPLAY 0.872340 (-5950 2975);
PAINT GREEN (-5950 2975);
DISPLAY INVISIBLE (-5950 2975);
FORCEPROP 1 LAST HDL_TAP TRUE
J 0
(-5625 2800);
DISPLAY 0.872340 (-5625 2800);
DISPLAY INVISIBLE (-5625 2800);
FORCEPROP 1 LAST PATH I52
J 0
(-5952 2925);
DISPLAY 0.872340 (-5952 2925);
PAINT GREEN (-5952 2925);
DISPLAY INVISIBLE (-5952 2925);
FORCEADD TAP..1
(-5950 3125);
FORCEPROP 3 LASTPIN (-6000 3125) SIG_NAME M_J_CPU0_SB_DQ<20>
J 0
(-5990 3135);
DISPLAY 0.659574 (-5990 3135);
PAINT MONO (-5990 3135);
DISPLAY INVISIBLE (-5990 3135);
FORCEPROP 1 LASTPIN (-6000 3125) BN 20
J 0
(-6012 3133);
DISPLAY 0.489362 (-6012 3133);
PAINT GREEN (-6012 3133);
FORCEPROP 2 LAST CDS_LIB mstr_standard
J 0
(-5950 3125);
DISPLAY 0.723404 (-5950 3125);
PAINT MONO (-5950 3125);
DISPLAY INVISIBLE (-5950 3125);
FORCEPROP 1 LAST BODY_TYPE PLUMBING
J 0
(-5950 3175);
DISPLAY 0.872340 (-5950 3175);
PAINT GREEN (-5950 3175);
DISPLAY INVISIBLE (-5950 3175);
FORCEPROP 1 LAST HDL_TAP TRUE
J 0
(-5625 3000);
DISPLAY 0.872340 (-5625 3000);
DISPLAY INVISIBLE (-5625 3000);
FORCEPROP 1 LAST PATH I53
J 0
(-5952 3125);
DISPLAY 0.872340 (-5952 3125);
PAINT GREEN (-5952 3125);
DISPLAY INVISIBLE (-5952 3125);
FORCEADD TAP..1
(-5950 3075);
FORCEPROP 3 LASTPIN (-6000 3075) SIG_NAME M_J_CPU0_SB_DQ<19>
J 0
(-5990 3085);
DISPLAY 0.659574 (-5990 3085);
PAINT MONO (-5990 3085);
DISPLAY INVISIBLE (-5990 3085);
FORCEPROP 1 LASTPIN (-6000 3075) BN 19
J 0
(-6012 3083);
DISPLAY 0.489362 (-6012 3083);
PAINT GREEN (-6012 3083);
FORCEPROP 2 LAST CDS_LIB mstr_standard
J 0
(-5950 3075);
DISPLAY 0.723404 (-5950 3075);
PAINT MONO (-5950 3075);
DISPLAY INVISIBLE (-5950 3075);
FORCEPROP 1 LAST BODY_TYPE PLUMBING
J 0
(-5950 3125);
DISPLAY 0.872340 (-5950 3125);
PAINT GREEN (-5950 3125);
DISPLAY INVISIBLE (-5950 3125);
FORCEPROP 1 LAST HDL_TAP TRUE
J 0
(-5625 2950);
DISPLAY 0.872340 (-5625 2950);
DISPLAY INVISIBLE (-5625 2950);
FORCEPROP 1 LAST PATH I54
J 0
(-5952 3075);
DISPLAY 0.872340 (-5952 3075);
PAINT GREEN (-5952 3075);
DISPLAY INVISIBLE (-5952 3075);
FORCEADD TAP..1
(-5950 3025);
FORCEPROP 3 LASTPIN (-6000 3025) SIG_NAME M_J_CPU0_SB_DQ<18>
J 0
(-5990 3035);
DISPLAY 0.659574 (-5990 3035);
PAINT MONO (-5990 3035);
DISPLAY INVISIBLE (-5990 3035);
FORCEPROP 1 LASTPIN (-6000 3025) BN 18
J 0
(-6012 3033);
DISPLAY 0.489362 (-6012 3033);
PAINT GREEN (-6012 3033);
FORCEPROP 2 LAST CDS_LIB mstr_standard
J 0
(-5950 3025);
DISPLAY 0.723404 (-5950 3025);
PAINT MONO (-5950 3025);
DISPLAY INVISIBLE (-5950 3025);
FORCEPROP 1 LAST BODY_TYPE PLUMBING
J 0
(-5950 3075);
DISPLAY 0.872340 (-5950 3075);
PAINT GREEN (-5950 3075);
DISPLAY INVISIBLE (-5950 3075);
FORCEPROP 1 LAST HDL_TAP TRUE
J 0
(-5625 2900);
DISPLAY 0.872340 (-5625 2900);
DISPLAY INVISIBLE (-5625 2900);
FORCEPROP 1 LAST PATH I55
J 0
(-5952 3025);
DISPLAY 0.872340 (-5952 3025);
PAINT GREEN (-5952 3025);
DISPLAY INVISIBLE (-5952 3025);
FORCEADD TAP..1
(-5950 3175);
FORCEPROP 3 LASTPIN (-6000 3175) SIG_NAME M_J_CPU0_SB_DQ<21>
J 0
(-5990 3185);
DISPLAY 0.659574 (-5990 3185);
PAINT MONO (-5990 3185);
DISPLAY INVISIBLE (-5990 3185);
FORCEPROP 1 LASTPIN (-6000 3175) BN 21
J 0
(-6012 3183);
DISPLAY 0.489362 (-6012 3183);
PAINT GREEN (-6012 3183);
FORCEPROP 2 LAST CDS_LIB mstr_standard
J 0
(-5950 3175);
DISPLAY 0.723404 (-5950 3175);
PAINT MONO (-5950 3175);
DISPLAY INVISIBLE (-5950 3175);
FORCEPROP 1 LAST BODY_TYPE PLUMBING
J 0
(-5950 3225);
DISPLAY 0.872340 (-5950 3225);
PAINT GREEN (-5950 3225);
DISPLAY INVISIBLE (-5950 3225);
FORCEPROP 1 LAST HDL_TAP TRUE
J 0
(-5625 3050);
DISPLAY 0.872340 (-5625 3050);
DISPLAY INVISIBLE (-5625 3050);
FORCEPROP 1 LAST PATH I56
J 0
(-5952 3175);
DISPLAY 0.872340 (-5952 3175);
PAINT GREEN (-5952 3175);
DISPLAY INVISIBLE (-5952 3175);
FORCEADD TAP..1
(-5950 3225);
FORCEPROP 3 LASTPIN (-6000 3225) SIG_NAME M_J_CPU0_SB_DQ<22>
J 0
(-5990 3235);
DISPLAY 0.659574 (-5990 3235);
PAINT MONO (-5990 3235);
DISPLAY INVISIBLE (-5990 3235);
FORCEPROP 1 LASTPIN (-6000 3225) BN 22
J 0
(-6012 3233);
DISPLAY 0.489362 (-6012 3233);
PAINT GREEN (-6012 3233);
FORCEPROP 2 LAST CDS_LIB mstr_standard
J 0
(-5950 3225);
DISPLAY 0.723404 (-5950 3225);
PAINT MONO (-5950 3225);
DISPLAY INVISIBLE (-5950 3225);
FORCEPROP 1 LAST BODY_TYPE PLUMBING
J 0
(-5950 3275);
DISPLAY 0.872340 (-5950 3275);
PAINT GREEN (-5950 3275);
DISPLAY INVISIBLE (-5950 3275);
FORCEPROP 1 LAST HDL_TAP TRUE
J 0
(-5625 3100);
DISPLAY 0.872340 (-5625 3100);
DISPLAY INVISIBLE (-5625 3100);
FORCEPROP 1 LAST PATH I57
J 0
(-5952 3225);
DISPLAY 0.872340 (-5952 3225);
PAINT GREEN (-5952 3225);
DISPLAY INVISIBLE (-5952 3225);
FORCEADD TAP..1
(-5950 3375);
FORCEPROP 3 LASTPIN (-6000 3375) SIG_NAME M_J_CPU0_SB_DQ<25>
J 0
(-5990 3385);
DISPLAY 0.659574 (-5990 3385);
PAINT MONO (-5990 3385);
DISPLAY INVISIBLE (-5990 3385);
FORCEPROP 1 LASTPIN (-6000 3375) BN 25
J 0
(-6012 3383);
DISPLAY 0.489362 (-6012 3383);
PAINT GREEN (-6012 3383);
FORCEPROP 2 LAST CDS_LIB mstr_standard
J 0
(-5950 3375);
DISPLAY 0.723404 (-5950 3375);
PAINT MONO (-5950 3375);
DISPLAY INVISIBLE (-5950 3375);
FORCEPROP 1 LAST BODY_TYPE PLUMBING
J 0
(-5950 3425);
DISPLAY 0.872340 (-5950 3425);
PAINT GREEN (-5950 3425);
DISPLAY INVISIBLE (-5950 3425);
FORCEPROP 1 LAST HDL_TAP TRUE
J 0
(-5625 3250);
DISPLAY 0.872340 (-5625 3250);
DISPLAY INVISIBLE (-5625 3250);
FORCEPROP 1 LAST PATH I58
J 0
(-5952 3375);
DISPLAY 0.872340 (-5952 3375);
PAINT GREEN (-5952 3375);
DISPLAY INVISIBLE (-5952 3375);
FORCEADD TAP..1
(-5950 3325);
FORCEPROP 3 LASTPIN (-6000 3325) SIG_NAME M_J_CPU0_SB_DQ<24>
J 0
(-5990 3335);
DISPLAY 0.659574 (-5990 3335);
PAINT MONO (-5990 3335);
DISPLAY INVISIBLE (-5990 3335);
FORCEPROP 1 LASTPIN (-6000 3325) BN 24
J 0
(-6012 3333);
DISPLAY 0.489362 (-6012 3333);
PAINT GREEN (-6012 3333);
FORCEPROP 2 LAST CDS_LIB mstr_standard
J 0
(-5950 3325);
DISPLAY 0.723404 (-5950 3325);
PAINT MONO (-5950 3325);
DISPLAY INVISIBLE (-5950 3325);
FORCEPROP 1 LAST BODY_TYPE PLUMBING
J 0
(-5950 3375);
DISPLAY 0.872340 (-5950 3375);
PAINT GREEN (-5950 3375);
DISPLAY INVISIBLE (-5950 3375);
FORCEPROP 1 LAST HDL_TAP TRUE
J 0
(-5625 3200);
DISPLAY 0.872340 (-5625 3200);
DISPLAY INVISIBLE (-5625 3200);
FORCEPROP 1 LAST PATH I59
J 0
(-5952 3325);
DISPLAY 0.872340 (-5952 3325);
PAINT GREEN (-5952 3325);
DISPLAY INVISIBLE (-5952 3325);
FORCEADD OFFPAGE..1
(-8525 2825);
FORCEPROP 2 LAST $XR0 95 
J 0
(-8746 2825);
DISPLAY 0.638298 (-8746 2825);
PAINT MONO (-8746 2825);
FORCEPROP 2 LAST CDS_LIB mstr_standard
J 0
(-8525 2825);
DISPLAY 0.808511 (-8525 2825);
DISPLAY INVISIBLE (-8525 2825);
FORCEPROP 1 LAST OFFPAGE TRUE
J 0
(-8200 2700);
DISPLAY 0.872340 (-8200 2700);
PAINT GREEN (-8200 2700);
DISPLAY INVISIBLE (-8200 2700);
FORCEPROP 1 LAST COMMENT_BODY TRUE
J 0
(-8400 2725);
DISPLAY 0.872340 (-8400 2725);
PAINT GREEN (-8400 2725);
DISPLAY INVISIBLE (-8400 2725);
FORCEPROP 2 LAST PATH I6
J 0
(-8775 2875);
DISPLAY 1.021277 (-8775 2875);
DISPLAY INVISIBLE (-8775 2875);
FORCEADD TAP..1
(-5950 3275);
FORCEPROP 3 LASTPIN (-6000 3275) SIG_NAME M_J_CPU0_SB_DQ<23>
J 0
(-5990 3285);
DISPLAY 0.659574 (-5990 3285);
PAINT MONO (-5990 3285);
DISPLAY INVISIBLE (-5990 3285);
FORCEPROP 1 LASTPIN (-6000 3275) BN 23
J 0
(-6012 3283);
DISPLAY 0.489362 (-6012 3283);
PAINT GREEN (-6012 3283);
FORCEPROP 2 LAST CDS_LIB mstr_standard
J 0
(-5950 3275);
DISPLAY 0.723404 (-5950 3275);
PAINT MONO (-5950 3275);
DISPLAY INVISIBLE (-5950 3275);
FORCEPROP 1 LAST BODY_TYPE PLUMBING
J 0
(-5950 3325);
DISPLAY 0.872340 (-5950 3325);
PAINT GREEN (-5950 3325);
DISPLAY INVISIBLE (-5950 3325);
FORCEPROP 1 LAST HDL_TAP TRUE
J 0
(-5625 3150);
DISPLAY 0.872340 (-5625 3150);
DISPLAY INVISIBLE (-5625 3150);
FORCEPROP 1 LAST PATH I60
J 0
(-5952 3275);
DISPLAY 0.872340 (-5952 3275);
PAINT GREEN (-5952 3275);
DISPLAY INVISIBLE (-5952 3275);
FORCEADD TAP..1
(-5950 3425);
FORCEPROP 3 LASTPIN (-6000 3425) SIG_NAME M_J_CPU0_SB_DQ<26>
J 0
(-5990 3435);
DISPLAY 0.659574 (-5990 3435);
PAINT MONO (-5990 3435);
DISPLAY INVISIBLE (-5990 3435);
FORCEPROP 1 LASTPIN (-6000 3425) BN 26
J 0
(-6012 3433);
DISPLAY 0.489362 (-6012 3433);
PAINT GREEN (-6012 3433);
FORCEPROP 2 LAST CDS_LIB mstr_standard
J 0
(-5950 3425);
DISPLAY 0.723404 (-5950 3425);
PAINT MONO (-5950 3425);
DISPLAY INVISIBLE (-5950 3425);
FORCEPROP 1 LAST BODY_TYPE PLUMBING
J 0
(-5950 3475);
DISPLAY 0.872340 (-5950 3475);
PAINT GREEN (-5950 3475);
DISPLAY INVISIBLE (-5950 3475);
FORCEPROP 1 LAST HDL_TAP TRUE
J 0
(-5625 3300);
DISPLAY 0.872340 (-5625 3300);
DISPLAY INVISIBLE (-5625 3300);
FORCEPROP 1 LAST PATH I61
J 0
(-5952 3425);
DISPLAY 0.872340 (-5952 3425);
PAINT GREEN (-5952 3425);
DISPLAY INVISIBLE (-5952 3425);
FORCEADD TAP..1
(-5950 3475);
FORCEPROP 3 LASTPIN (-6000 3475) SIG_NAME M_J_CPU0_SB_DQ<27>
J 0
(-5990 3485);
DISPLAY 0.659574 (-5990 3485);
PAINT MONO (-5990 3485);
DISPLAY INVISIBLE (-5990 3485);
FORCEPROP 1 LASTPIN (-6000 3475) BN 27
J 0
(-6012 3483);
DISPLAY 0.489362 (-6012 3483);
PAINT GREEN (-6012 3483);
FORCEPROP 2 LAST CDS_LIB mstr_standard
J 0
(-5950 3475);
DISPLAY 0.723404 (-5950 3475);
PAINT MONO (-5950 3475);
DISPLAY INVISIBLE (-5950 3475);
FORCEPROP 1 LAST BODY_TYPE PLUMBING
J 0
(-5950 3525);
DISPLAY 0.872340 (-5950 3525);
PAINT GREEN (-5950 3525);
DISPLAY INVISIBLE (-5950 3525);
FORCEPROP 1 LAST HDL_TAP TRUE
J 0
(-5625 3350);
DISPLAY 0.872340 (-5625 3350);
DISPLAY INVISIBLE (-5625 3350);
FORCEPROP 1 LAST PATH I62
J 0
(-5952 3475);
DISPLAY 0.872340 (-5952 3475);
PAINT GREEN (-5952 3475);
DISPLAY INVISIBLE (-5952 3475);
FORCEADD TAP..1
(-5950 3625);
FORCEPROP 3 LASTPIN (-6000 3625) SIG_NAME M_J_CPU0_SB_DQ<30>
J 0
(-5990 3635);
DISPLAY 0.659574 (-5990 3635);
PAINT MONO (-5990 3635);
DISPLAY INVISIBLE (-5990 3635);
FORCEPROP 1 LASTPIN (-6000 3625) BN 30
J 0
(-6012 3633);
DISPLAY 0.489362 (-6012 3633);
PAINT GREEN (-6012 3633);
FORCEPROP 2 LAST CDS_LIB mstr_standard
J 0
(-5950 3625);
DISPLAY 0.723404 (-5950 3625);
PAINT MONO (-5950 3625);
DISPLAY INVISIBLE (-5950 3625);
FORCEPROP 1 LAST BODY_TYPE PLUMBING
J 0
(-5950 3675);
DISPLAY 0.872340 (-5950 3675);
PAINT GREEN (-5950 3675);
DISPLAY INVISIBLE (-5950 3675);
FORCEPROP 1 LAST HDL_TAP TRUE
J 0
(-5625 3500);
DISPLAY 0.872340 (-5625 3500);
DISPLAY INVISIBLE (-5625 3500);
FORCEPROP 1 LAST PATH I63
J 0
(-5952 3625);
DISPLAY 0.872340 (-5952 3625);
PAINT GREEN (-5952 3625);
DISPLAY INVISIBLE (-5952 3625);
FORCEADD TAP..1
(-5950 3575);
FORCEPROP 3 LASTPIN (-6000 3575) SIG_NAME M_J_CPU0_SB_DQ<29>
J 0
(-5990 3585);
DISPLAY 0.659574 (-5990 3585);
PAINT MONO (-5990 3585);
DISPLAY INVISIBLE (-5990 3585);
FORCEPROP 1 LASTPIN (-6000 3575) BN 29
J 0
(-6012 3583);
DISPLAY 0.489362 (-6012 3583);
PAINT GREEN (-6012 3583);
FORCEPROP 2 LAST CDS_LIB mstr_standard
J 0
(-5950 3575);
DISPLAY 0.723404 (-5950 3575);
PAINT MONO (-5950 3575);
DISPLAY INVISIBLE (-5950 3575);
FORCEPROP 1 LAST BODY_TYPE PLUMBING
J 0
(-5950 3625);
DISPLAY 0.872340 (-5950 3625);
PAINT GREEN (-5950 3625);
DISPLAY INVISIBLE (-5950 3625);
FORCEPROP 1 LAST HDL_TAP TRUE
J 0
(-5625 3450);
DISPLAY 0.872340 (-5625 3450);
DISPLAY INVISIBLE (-5625 3450);
FORCEPROP 1 LAST PATH I64
J 0
(-5952 3575);
DISPLAY 0.872340 (-5952 3575);
PAINT GREEN (-5952 3575);
DISPLAY INVISIBLE (-5952 3575);
FORCEADD TAP..1
(-5950 3525);
FORCEPROP 3 LASTPIN (-6000 3525) SIG_NAME M_J_CPU0_SB_DQ<28>
J 0
(-5990 3535);
DISPLAY 0.659574 (-5990 3535);
PAINT MONO (-5990 3535);
DISPLAY INVISIBLE (-5990 3535);
FORCEPROP 1 LASTPIN (-6000 3525) BN 28
J 0
(-6012 3533);
DISPLAY 0.489362 (-6012 3533);
PAINT GREEN (-6012 3533);
FORCEPROP 2 LAST CDS_LIB mstr_standard
J 0
(-5950 3525);
DISPLAY 0.723404 (-5950 3525);
PAINT MONO (-5950 3525);
DISPLAY INVISIBLE (-5950 3525);
FORCEPROP 1 LAST BODY_TYPE PLUMBING
J 0
(-5950 3575);
DISPLAY 0.872340 (-5950 3575);
PAINT GREEN (-5950 3575);
DISPLAY INVISIBLE (-5950 3575);
FORCEPROP 1 LAST HDL_TAP TRUE
J 0
(-5625 3400);
DISPLAY 0.872340 (-5625 3400);
DISPLAY INVISIBLE (-5625 3400);
FORCEPROP 1 LAST PATH I65
J 0
(-5952 3525);
DISPLAY 0.872340 (-5952 3525);
PAINT GREEN (-5952 3525);
DISPLAY INVISIBLE (-5952 3525);
FORCEADD TAP..1
(-5950 3675);
FORCEPROP 3 LASTPIN (-6000 3675) SIG_NAME M_J_CPU0_SB_DQ<31>
J 0
(-5990 3685);
DISPLAY 0.659574 (-5990 3685);
PAINT MONO (-5990 3685);
DISPLAY INVISIBLE (-5990 3685);
FORCEPROP 1 LASTPIN (-6000 3675) BN 31
J 0
(-6012 3683);
DISPLAY 0.489362 (-6012 3683);
PAINT GREEN (-6012 3683);
FORCEPROP 2 LAST CDS_LIB mstr_standard
J 0
(-5950 3675);
DISPLAY 0.723404 (-5950 3675);
PAINT MONO (-5950 3675);
DISPLAY INVISIBLE (-5950 3675);
FORCEPROP 1 LAST BODY_TYPE PLUMBING
J 0
(-5950 3725);
DISPLAY 0.872340 (-5950 3725);
PAINT GREEN (-5950 3725);
DISPLAY INVISIBLE (-5950 3725);
FORCEPROP 1 LAST HDL_TAP TRUE
J 0
(-5625 3550);
DISPLAY 0.872340 (-5625 3550);
DISPLAY INVISIBLE (-5625 3550);
FORCEPROP 1 LAST PATH I66
J 0
(-5952 3675);
DISPLAY 0.872340 (-5952 3675);
PAINT GREEN (-5952 3675);
DISPLAY INVISIBLE (-5952 3675);
FORCEADD OFFPAGE..5
(-8050 2975);
FORCEPROP 2 LAST $XR0 19 
J 0
(-8304 2975);
DISPLAY 0.638298 (-8304 2975);
PAINT MONO (-8304 2975);
FORCEPROP 2 LAST CDS_LIB mstr_standard
J 0
(-8050 2975);
DISPLAY INVISIBLE (-8050 2975);
FORCEPROP 1 LAST OFFPAGE TRUE
J 0
(-7725 2850);
DISPLAY 0.872340 (-7725 2850);
PAINT GREEN (-7725 2850);
DISPLAY INVISIBLE (-7725 2850);
FORCEPROP 1 LAST COMMENT_BODY TRUE
J 0
(-7950 2900);
DISPLAY 0.872340 (-7950 2900);
PAINT GREEN (-7950 2900);
DISPLAY INVISIBLE (-7950 2900);
FORCEPROP 2 LAST PATH I7
J 0
(-8000 3050);
DISPLAY 1.021277 (-8000 3050);
DISPLAY INVISIBLE (-8000 3050);
FORCEADD OFFPAGE..3
(-5200 3725);
FORCEPROP 2 LAST $XR0 19 
J 0
(-4896 3725);
DISPLAY 0.638298 (-4896 3725);
PAINT MONO (-4896 3725);
FORCEPROP 2 LAST CDS_LIB mstr_standard
J 0
(-5200 3725);
DISPLAY 0.723404 (-5200 3725);
PAINT MONO (-5200 3725);
DISPLAY INVISIBLE (-5200 3725);
FORCEPROP 1 LAST OFFPAGE TRUE
J 0
(-4875 3600);
DISPLAY 0.872340 (-4875 3600);
PAINT GREEN (-4875 3600);
DISPLAY INVISIBLE (-4875 3600);
FORCEPROP 1 LAST COMMENT_BODY TRUE
J 0
(-5250 3625);
DISPLAY 0.872340 (-5250 3625);
PAINT GREEN (-5250 3625);
DISPLAY INVISIBLE (-5250 3625);
FORCEPROP 2 LAST PATH I74
J 0
(-5000 3800);
DISPLAY 1.021277 (-5000 3800);
DISPLAY INVISIBLE (-5000 3800);
FORCEADD TAP..1
R 2
(-7650 3775);
FORCEPROP 3 LASTPIN (-7600 3775) SIG_NAME M_J_CPU0_SA_CB<4>
J 0
(-7590 3785);
DISPLAY 0.659574 (-7590 3785);
PAINT MONO (-7590 3785);
DISPLAY INVISIBLE (-7590 3785);
FORCEPROP 1 LASTPIN (-7600 3775) BN 4
J 2
(-7588 3783);
DISPLAY 0.489362 (-7588 3783);
PAINT GREEN (-7588 3783);
FORCEPROP 2 LAST CDS_LIB mstr_standard
J 0
(-7650 3775);
DISPLAY 0.723404 (-7650 3775);
PAINT MONO (-7650 3775);
DISPLAY INVISIBLE (-7650 3775);
FORCEPROP 1 LAST BODY_TYPE PLUMBING
J 2
(-7650 3825);
DISPLAY 0.872340 (-7650 3825);
PAINT GREEN (-7650 3825);
DISPLAY INVISIBLE (-7650 3825);
FORCEPROP 1 LAST HDL_TAP TRUE
J 2
(-7975 3650);
DISPLAY 0.872340 (-7975 3650);
DISPLAY INVISIBLE (-7975 3650);
FORCEPROP 1 LAST PATH I76
J 2
(-7648 3775);
DISPLAY 0.872340 (-7648 3775);
PAINT GREEN (-7648 3775);
DISPLAY INVISIBLE (-7648 3775);
FORCEADD TAP..1
R 2
(-7650 3825);
FORCEPROP 3 LASTPIN (-7600 3825) SIG_NAME M_J_CPU0_SA_CB<5>
J 0
(-7590 3835);
DISPLAY 0.659574 (-7590 3835);
PAINT MONO (-7590 3835);
DISPLAY INVISIBLE (-7590 3835);
FORCEPROP 1 LASTPIN (-7600 3825) BN 5
J 2
(-7588 3833);
DISPLAY 0.489362 (-7588 3833);
PAINT GREEN (-7588 3833);
FORCEPROP 2 LAST CDS_LIB mstr_standard
J 0
(-7650 3825);
DISPLAY 0.723404 (-7650 3825);
PAINT MONO (-7650 3825);
DISPLAY INVISIBLE (-7650 3825);
FORCEPROP 1 LAST BODY_TYPE PLUMBING
J 2
(-7650 3875);
DISPLAY 0.872340 (-7650 3875);
PAINT GREEN (-7650 3875);
DISPLAY INVISIBLE (-7650 3875);
FORCEPROP 1 LAST HDL_TAP TRUE
J 2
(-7975 3700);
DISPLAY 0.872340 (-7975 3700);
DISPLAY INVISIBLE (-7975 3700);
FORCEPROP 1 LAST PATH I77
J 2
(-7648 3825);
DISPLAY 0.872340 (-7648 3825);
PAINT GREEN (-7648 3825);
DISPLAY INVISIBLE (-7648 3825);
FORCEADD TAP..1
R 2
(-7650 3875);
FORCEPROP 3 LASTPIN (-7600 3875) SIG_NAME M_J_CPU0_SA_CB<6>
J 0
(-7590 3885);
DISPLAY 0.659574 (-7590 3885);
PAINT MONO (-7590 3885);
DISPLAY INVISIBLE (-7590 3885);
FORCEPROP 1 LASTPIN (-7600 3875) BN 6
J 2
(-7588 3883);
DISPLAY 0.489362 (-7588 3883);
PAINT GREEN (-7588 3883);
FORCEPROP 2 LAST CDS_LIB mstr_standard
J 0
(-7650 3875);
DISPLAY 0.723404 (-7650 3875);
PAINT MONO (-7650 3875);
DISPLAY INVISIBLE (-7650 3875);
FORCEPROP 1 LAST BODY_TYPE PLUMBING
J 2
(-7650 3925);
DISPLAY 0.872340 (-7650 3925);
PAINT GREEN (-7650 3925);
DISPLAY INVISIBLE (-7650 3925);
FORCEPROP 1 LAST HDL_TAP TRUE
J 2
(-7975 3750);
DISPLAY 0.872340 (-7975 3750);
DISPLAY INVISIBLE (-7975 3750);
FORCEPROP 1 LAST PATH I78
J 2
(-7648 3875);
DISPLAY 0.872340 (-7648 3875);
PAINT GREEN (-7648 3875);
DISPLAY INVISIBLE (-7648 3875);
FORCEADD TAP..1
R 2
(-7650 3925);
FORCEPROP 3 LASTPIN (-7600 3925) SIG_NAME M_J_CPU0_SA_CB<7>
J 0
(-7590 3935);
DISPLAY 0.659574 (-7590 3935);
PAINT MONO (-7590 3935);
DISPLAY INVISIBLE (-7590 3935);
FORCEPROP 1 LASTPIN (-7600 3925) BN 7
J 2
(-7588 3933);
DISPLAY 0.489362 (-7588 3933);
PAINT GREEN (-7588 3933);
FORCEPROP 2 LAST CDS_LIB mstr_standard
J 0
(-7650 3925);
DISPLAY 0.723404 (-7650 3925);
PAINT MONO (-7650 3925);
DISPLAY INVISIBLE (-7650 3925);
FORCEPROP 1 LAST BODY_TYPE PLUMBING
J 2
(-7650 3975);
DISPLAY 0.872340 (-7650 3975);
PAINT GREEN (-7650 3975);
DISPLAY INVISIBLE (-7650 3975);
FORCEPROP 1 LAST HDL_TAP TRUE
J 2
(-7975 3800);
DISPLAY 0.872340 (-7975 3800);
DISPLAY INVISIBLE (-7975 3800);
FORCEPROP 1 LAST PATH I79
J 2
(-7648 3925);
DISPLAY 0.872340 (-7648 3925);
PAINT GREEN (-7648 3925);
DISPLAY INVISIBLE (-7648 3925);
FORCEADD OFFPAGE..1
(-8050 3025);
FORCEPROP 2 LAST $XR0 19 
J 0
(-8301 3025);
DISPLAY 0.638298 (-8301 3025);
PAINT MONO (-8301 3025);
FORCEPROP 2 LAST CDS_LIB mstr_standard
J 0
(-8050 3025);
DISPLAY 0.808511 (-8050 3025);
DISPLAY INVISIBLE (-8050 3025);
FORCEPROP 1 LAST OFFPAGE TRUE
J 0
(-7725 2900);
DISPLAY 0.872340 (-7725 2900);
PAINT GREEN (-7725 2900);
DISPLAY INVISIBLE (-7725 2900);
FORCEPROP 1 LAST COMMENT_BODY TRUE
J 0
(-7925 2925);
DISPLAY 0.872340 (-7925 2925);
PAINT GREEN (-7925 2925);
DISPLAY INVISIBLE (-7925 2925);
FORCEPROP 2 LAST PATH I8
J 0
(-8475 3075);
DISPLAY 1.021277 (-8475 3075);
DISPLAY INVISIBLE (-8475 3075);
FORCEADD TAP..1
R 2
(-7650 4625);
FORCEPROP 3 LASTPIN (-7600 4625) SIG_NAME M_J_CPU0_SB_CA<0>
J 0
(-7590 4635);
DISPLAY 0.659574 (-7590 4635);
PAINT MONO (-7590 4635);
DISPLAY INVISIBLE (-7590 4635);
FORCEPROP 1 LASTPIN (-7600 4625) BN 0
J 2
(-7588 4633);
DISPLAY 0.489362 (-7588 4633);
PAINT GREEN (-7588 4633);
FORCEPROP 2 LAST CDS_LIB mstr_standard
J 0
(-7650 4625);
DISPLAY 0.723404 (-7650 4625);
PAINT MONO (-7650 4625);
DISPLAY INVISIBLE (-7650 4625);
FORCEPROP 1 LAST BODY_TYPE PLUMBING
J 2
(-7650 4675);
DISPLAY 0.872340 (-7650 4675);
PAINT GREEN (-7650 4675);
DISPLAY INVISIBLE (-7650 4675);
FORCEPROP 1 LAST HDL_TAP TRUE
J 2
(-7975 4500);
DISPLAY 0.872340 (-7975 4500);
DISPLAY INVISIBLE (-7975 4500);
FORCEPROP 1 LAST PATH I80
J 2
(-7648 4625);
DISPLAY 0.872340 (-7648 4625);
PAINT GREEN (-7648 4625);
DISPLAY INVISIBLE (-7648 4625);
FORCEADD TAP..1
R 2
(-7650 4675);
FORCEPROP 3 LASTPIN (-7600 4675) SIG_NAME M_J_CPU0_SB_CA<1>
J 0
(-7590 4685);
DISPLAY 0.659574 (-7590 4685);
PAINT MONO (-7590 4685);
DISPLAY INVISIBLE (-7590 4685);
FORCEPROP 1 LASTPIN (-7600 4675) BN 1
J 2
(-7588 4683);
DISPLAY 0.489362 (-7588 4683);
PAINT GREEN (-7588 4683);
FORCEPROP 2 LAST CDS_LIB mstr_standard
J 0
(-7650 4675);
DISPLAY 0.723404 (-7650 4675);
PAINT MONO (-7650 4675);
DISPLAY INVISIBLE (-7650 4675);
FORCEPROP 1 LAST BODY_TYPE PLUMBING
J 2
(-7650 4725);
DISPLAY 0.872340 (-7650 4725);
PAINT GREEN (-7650 4725);
DISPLAY INVISIBLE (-7650 4725);
FORCEPROP 1 LAST HDL_TAP TRUE
J 2
(-7975 4550);
DISPLAY 0.872340 (-7975 4550);
DISPLAY INVISIBLE (-7975 4550);
FORCEPROP 1 LAST PATH I81
J 2
(-7648 4675);
DISPLAY 0.872340 (-7648 4675);
PAINT GREEN (-7648 4675);
DISPLAY INVISIBLE (-7648 4675);
FORCEADD TAP..1
R 2
(-7650 4725);
FORCEPROP 3 LASTPIN (-7600 4725) SIG_NAME M_J_CPU0_SB_CA<2>
J 0
(-7590 4735);
DISPLAY 0.659574 (-7590 4735);
PAINT MONO (-7590 4735);
DISPLAY INVISIBLE (-7590 4735);
FORCEPROP 1 LASTPIN (-7600 4725) BN 2
J 2
(-7588 4733);
DISPLAY 0.489362 (-7588 4733);
PAINT GREEN (-7588 4733);
FORCEPROP 2 LAST CDS_LIB mstr_standard
J 0
(-7650 4725);
DISPLAY 0.723404 (-7650 4725);
PAINT MONO (-7650 4725);
DISPLAY INVISIBLE (-7650 4725);
FORCEPROP 1 LAST BODY_TYPE PLUMBING
J 2
(-7650 4775);
DISPLAY 0.872340 (-7650 4775);
PAINT GREEN (-7650 4775);
DISPLAY INVISIBLE (-7650 4775);
FORCEPROP 1 LAST HDL_TAP TRUE
J 2
(-7975 4600);
DISPLAY 0.872340 (-7975 4600);
DISPLAY INVISIBLE (-7975 4600);
FORCEPROP 1 LAST PATH I82
J 2
(-7648 4725);
DISPLAY 0.872340 (-7648 4725);
PAINT GREEN (-7648 4725);
DISPLAY INVISIBLE (-7648 4725);
FORCEADD TAP..1
R 2
(-7650 4775);
FORCEPROP 3 LASTPIN (-7600 4775) SIG_NAME M_J_CPU0_SB_CA<3>
J 0
(-7590 4785);
DISPLAY 0.659574 (-7590 4785);
PAINT MONO (-7590 4785);
DISPLAY INVISIBLE (-7590 4785);
FORCEPROP 1 LASTPIN (-7600 4775) BN 3
J 2
(-7588 4783);
DISPLAY 0.489362 (-7588 4783);
PAINT GREEN (-7588 4783);
FORCEPROP 2 LAST CDS_LIB mstr_standard
J 0
(-7650 4775);
DISPLAY 0.723404 (-7650 4775);
PAINT MONO (-7650 4775);
DISPLAY INVISIBLE (-7650 4775);
FORCEPROP 1 LAST BODY_TYPE PLUMBING
J 2
(-7650 4825);
DISPLAY 0.872340 (-7650 4825);
PAINT GREEN (-7650 4825);
DISPLAY INVISIBLE (-7650 4825);
FORCEPROP 1 LAST HDL_TAP TRUE
J 2
(-7975 4650);
DISPLAY 0.872340 (-7975 4650);
DISPLAY INVISIBLE (-7975 4650);
FORCEPROP 1 LAST PATH I83
J 2
(-7648 4775);
DISPLAY 0.872340 (-7648 4775);
PAINT GREEN (-7648 4775);
DISPLAY INVISIBLE (-7648 4775);
FORCEADD TAP..1
R 2
(-7650 4825);
FORCEPROP 3 LASTPIN (-7600 4825) SIG_NAME M_J_CPU0_SB_CA<4>
J 0
(-7590 4835);
DISPLAY 0.659574 (-7590 4835);
PAINT MONO (-7590 4835);
DISPLAY INVISIBLE (-7590 4835);
FORCEPROP 1 LASTPIN (-7600 4825) BN 4
J 2
(-7588 4833);
DISPLAY 0.489362 (-7588 4833);
PAINT GREEN (-7588 4833);
FORCEPROP 2 LAST CDS_LIB mstr_standard
J 0
(-7650 4825);
DISPLAY 0.723404 (-7650 4825);
PAINT MONO (-7650 4825);
DISPLAY INVISIBLE (-7650 4825);
FORCEPROP 1 LAST BODY_TYPE PLUMBING
J 2
(-7650 4875);
DISPLAY 0.872340 (-7650 4875);
PAINT GREEN (-7650 4875);
DISPLAY INVISIBLE (-7650 4875);
FORCEPROP 1 LAST HDL_TAP TRUE
J 2
(-7975 4700);
DISPLAY 0.872340 (-7975 4700);
DISPLAY INVISIBLE (-7975 4700);
FORCEPROP 1 LAST PATH I84
J 2
(-7648 4825);
DISPLAY 0.872340 (-7648 4825);
PAINT GREEN (-7648 4825);
DISPLAY INVISIBLE (-7648 4825);
FORCEADD TAP..1
R 2
(-7650 4875);
FORCEPROP 3 LASTPIN (-7600 4875) SIG_NAME M_J_CPU0_SB_CA<5>
J 0
(-7590 4885);
DISPLAY 0.659574 (-7590 4885);
PAINT MONO (-7590 4885);
DISPLAY INVISIBLE (-7590 4885);
FORCEPROP 1 LASTPIN (-7600 4875) BN 5
J 2
(-7588 4883);
DISPLAY 0.489362 (-7588 4883);
PAINT GREEN (-7588 4883);
FORCEPROP 2 LAST CDS_LIB mstr_standard
J 0
(-7650 4875);
DISPLAY 0.723404 (-7650 4875);
PAINT MONO (-7650 4875);
DISPLAY INVISIBLE (-7650 4875);
FORCEPROP 1 LAST BODY_TYPE PLUMBING
J 2
(-7650 4925);
DISPLAY 0.872340 (-7650 4925);
PAINT GREEN (-7650 4925);
DISPLAY INVISIBLE (-7650 4925);
FORCEPROP 1 LAST HDL_TAP TRUE
J 2
(-7975 4750);
DISPLAY 0.872340 (-7975 4750);
DISPLAY INVISIBLE (-7975 4750);
FORCEPROP 1 LAST PATH I85
J 2
(-7648 4875);
DISPLAY 0.872340 (-7648 4875);
PAINT GREEN (-7648 4875);
DISPLAY INVISIBLE (-7648 4875);
FORCEADD TAP..1
R 2
(-7650 4925);
FORCEPROP 3 LASTPIN (-7600 4925) SIG_NAME M_J_CPU0_SB_CA<6>
J 0
(-7590 4935);
DISPLAY 0.659574 (-7590 4935);
PAINT MONO (-7590 4935);
DISPLAY INVISIBLE (-7590 4935);
FORCEPROP 1 LASTPIN (-7600 4925) BN 6
J 2
(-7588 4933);
DISPLAY 0.489362 (-7588 4933);
PAINT GREEN (-7588 4933);
FORCEPROP 2 LAST CDS_LIB mstr_standard
J 0
(-7650 4925);
DISPLAY 0.723404 (-7650 4925);
PAINT MONO (-7650 4925);
DISPLAY INVISIBLE (-7650 4925);
FORCEPROP 1 LAST BODY_TYPE PLUMBING
J 2
(-7650 4975);
DISPLAY 0.872340 (-7650 4975);
PAINT GREEN (-7650 4975);
DISPLAY INVISIBLE (-7650 4975);
FORCEPROP 1 LAST HDL_TAP TRUE
J 2
(-7975 4800);
DISPLAY 0.872340 (-7975 4800);
DISPLAY INVISIBLE (-7975 4800);
FORCEPROP 1 LAST PATH I86
J 2
(-7648 4925);
DISPLAY 0.872340 (-7648 4925);
PAINT GREEN (-7648 4925);
DISPLAY INVISIBLE (-7648 4925);
FORCEADD TAP..1
R 2
(-7650 5025);
FORCEPROP 3 LASTPIN (-7600 5025) SIG_NAME M_J_CPU0_SA_CA<0>
J 0
(-7590 5035);
DISPLAY 0.659574 (-7590 5035);
PAINT MONO (-7590 5035);
DISPLAY INVISIBLE (-7590 5035);
FORCEPROP 1 LASTPIN (-7600 5025) BN 0
J 2
(-7588 5033);
DISPLAY 0.489362 (-7588 5033);
PAINT GREEN (-7588 5033);
FORCEPROP 2 LAST CDS_LIB mstr_standard
J 0
(-7650 5025);
DISPLAY 0.723404 (-7650 5025);
PAINT MONO (-7650 5025);
DISPLAY INVISIBLE (-7650 5025);
FORCEPROP 1 LAST BODY_TYPE PLUMBING
J 2
(-7650 5075);
DISPLAY 0.872340 (-7650 5075);
PAINT GREEN (-7650 5075);
DISPLAY INVISIBLE (-7650 5075);
FORCEPROP 1 LAST HDL_TAP TRUE
J 2
(-7975 4900);
DISPLAY 0.872340 (-7975 4900);
DISPLAY INVISIBLE (-7975 4900);
FORCEPROP 1 LAST PATH I87
J 2
(-7648 5025);
DISPLAY 0.872340 (-7648 5025);
PAINT GREEN (-7648 5025);
DISPLAY INVISIBLE (-7648 5025);
FORCEADD TAP..1
R 2
(-7650 5075);
FORCEPROP 3 LASTPIN (-7600 5075) SIG_NAME M_J_CPU0_SA_CA<1>
J 0
(-7590 5085);
DISPLAY 0.659574 (-7590 5085);
PAINT MONO (-7590 5085);
DISPLAY INVISIBLE (-7590 5085);
FORCEPROP 1 LASTPIN (-7600 5075) BN 1
J 2
(-7588 5083);
DISPLAY 0.489362 (-7588 5083);
PAINT GREEN (-7588 5083);
FORCEPROP 2 LAST CDS_LIB mstr_standard
J 0
(-7650 5075);
DISPLAY 0.723404 (-7650 5075);
PAINT MONO (-7650 5075);
DISPLAY INVISIBLE (-7650 5075);
FORCEPROP 1 LAST BODY_TYPE PLUMBING
J 2
(-7650 5125);
DISPLAY 0.872340 (-7650 5125);
PAINT GREEN (-7650 5125);
DISPLAY INVISIBLE (-7650 5125);
FORCEPROP 1 LAST HDL_TAP TRUE
J 2
(-7975 4950);
DISPLAY 0.872340 (-7975 4950);
DISPLAY INVISIBLE (-7975 4950);
FORCEPROP 1 LAST PATH I88
J 2
(-7648 5075);
DISPLAY 0.872340 (-7648 5075);
PAINT GREEN (-7648 5075);
DISPLAY INVISIBLE (-7648 5075);
FORCEADD TAP..1
R 2
(-7650 5125);
FORCEPROP 3 LASTPIN (-7600 5125) SIG_NAME M_J_CPU0_SA_CA<2>
J 0
(-7590 5135);
DISPLAY 0.659574 (-7590 5135);
PAINT MONO (-7590 5135);
DISPLAY INVISIBLE (-7590 5135);
FORCEPROP 1 LASTPIN (-7600 5125) BN 2
J 2
(-7588 5133);
DISPLAY 0.489362 (-7588 5133);
PAINT GREEN (-7588 5133);
FORCEPROP 2 LAST CDS_LIB mstr_standard
J 0
(-7650 5125);
DISPLAY 0.723404 (-7650 5125);
PAINT MONO (-7650 5125);
DISPLAY INVISIBLE (-7650 5125);
FORCEPROP 1 LAST BODY_TYPE PLUMBING
J 2
(-7650 5175);
DISPLAY 0.872340 (-7650 5175);
PAINT GREEN (-7650 5175);
DISPLAY INVISIBLE (-7650 5175);
FORCEPROP 1 LAST HDL_TAP TRUE
J 2
(-7975 5000);
DISPLAY 0.872340 (-7975 5000);
DISPLAY INVISIBLE (-7975 5000);
FORCEPROP 1 LAST PATH I89
J 2
(-7648 5125);
DISPLAY 0.872340 (-7648 5125);
PAINT GREEN (-7648 5125);
DISPLAY INVISIBLE (-7648 5125);
FORCEADD VCC_CORE..1
(-8450 3375);
FORCEPROP 3 LASTPIN (-8450 3325) SIG_NAME P3V3_AUX\g
J 0
(-8440 3335);
DISPLAY 0.659574 (-8440 3335);
PAINT MONO (-8440 3335);
DISPLAY INVISIBLE (-8440 3335);
FORCEPROP 1 LAST HDL_POWER P3V3_AUX
J 1
(-8450 3425);
DISPLAY 0.489362 (-8450 3425);
PAINT GREEN (-8450 3425);
FORCEPROP 2 LAST CDS_LIB mstr_symbols
J 0
(-8450 3375);
PAINT MONO (-8450 3375);
DISPLAY INVISIBLE (-8450 3375);
FORCEPROP 0 LAST VOLTAGE 3.3
J 0
(-8725 3525);
DISPLAY 1.021277 (-8725 3525);
PAINT SKYBLUE (-8725 3525);
DISPLAY INVISIBLE (-8725 3525);
FORCEPROP 2 LAST ROOM PVCCINFAON_CPU0_CTRL
J 0
(-8450 3475);
DISPLAY 0.808511 (-8450 3475);
PAINT RED (-8450 3475);
DISPLAY INVISIBLE (-8450 3475);
FORCEPROP 1 LAST PATH I9
J 0
(-8400 3400);
DISPLAY 0.872340 (-8400 3400);
PAINT AQUA (-8400 3400);
DISPLAY INVISIBLE (-8400 3400);
FORCEADD TAP..1
R 2
(-7650 5175);
FORCEPROP 3 LASTPIN (-7600 5175) SIG_NAME M_J_CPU0_SA_CA<3>
J 0
(-7590 5185);
DISPLAY 0.659574 (-7590 5185);
PAINT MONO (-7590 5185);
DISPLAY INVISIBLE (-7590 5185);
FORCEPROP 1 LASTPIN (-7600 5175) BN 3
J 2
(-7588 5183);
DISPLAY 0.489362 (-7588 5183);
PAINT GREEN (-7588 5183);
FORCEPROP 2 LAST CDS_LIB mstr_standard
J 0
(-7650 5175);
DISPLAY 0.723404 (-7650 5175);
PAINT MONO (-7650 5175);
DISPLAY INVISIBLE (-7650 5175);
FORCEPROP 1 LAST BODY_TYPE PLUMBING
J 2
(-7650 5225);
DISPLAY 0.872340 (-7650 5225);
PAINT GREEN (-7650 5225);
DISPLAY INVISIBLE (-7650 5225);
FORCEPROP 1 LAST HDL_TAP TRUE
J 2
(-7975 5050);
DISPLAY 0.872340 (-7975 5050);
DISPLAY INVISIBLE (-7975 5050);
FORCEPROP 1 LAST PATH I90
J 2
(-7648 5175);
DISPLAY 0.872340 (-7648 5175);
PAINT GREEN (-7648 5175);
DISPLAY INVISIBLE (-7648 5175);
FORCEADD TAP..1
R 2
(-7650 5225);
FORCEPROP 3 LASTPIN (-7600 5225) SIG_NAME M_J_CPU0_SA_CA<4>
J 0
(-7590 5235);
DISPLAY 0.659574 (-7590 5235);
PAINT MONO (-7590 5235);
DISPLAY INVISIBLE (-7590 5235);
FORCEPROP 1 LASTPIN (-7600 5225) BN 4
J 2
(-7588 5233);
DISPLAY 0.489362 (-7588 5233);
PAINT GREEN (-7588 5233);
FORCEPROP 2 LAST CDS_LIB mstr_standard
J 0
(-7650 5225);
DISPLAY 0.723404 (-7650 5225);
PAINT MONO (-7650 5225);
DISPLAY INVISIBLE (-7650 5225);
FORCEPROP 1 LAST BODY_TYPE PLUMBING
J 2
(-7650 5275);
DISPLAY 0.872340 (-7650 5275);
PAINT GREEN (-7650 5275);
DISPLAY INVISIBLE (-7650 5275);
FORCEPROP 1 LAST HDL_TAP TRUE
J 2
(-7975 5100);
DISPLAY 0.872340 (-7975 5100);
DISPLAY INVISIBLE (-7975 5100);
FORCEPROP 1 LAST PATH I91
J 2
(-7648 5225);
DISPLAY 0.872340 (-7648 5225);
PAINT GREEN (-7648 5225);
DISPLAY INVISIBLE (-7648 5225);
FORCEADD TAP..1
R 2
(-7650 5275);
FORCEPROP 3 LASTPIN (-7600 5275) SIG_NAME M_J_CPU0_SA_CA<5>
J 0
(-7590 5285);
DISPLAY 0.659574 (-7590 5285);
PAINT MONO (-7590 5285);
DISPLAY INVISIBLE (-7590 5285);
FORCEPROP 1 LASTPIN (-7600 5275) BN 5
J 2
(-7588 5283);
DISPLAY 0.489362 (-7588 5283);
PAINT GREEN (-7588 5283);
FORCEPROP 2 LAST CDS_LIB mstr_standard
J 0
(-7650 5275);
DISPLAY 0.723404 (-7650 5275);
PAINT MONO (-7650 5275);
DISPLAY INVISIBLE (-7650 5275);
FORCEPROP 1 LAST BODY_TYPE PLUMBING
J 2
(-7650 5325);
DISPLAY 0.872340 (-7650 5325);
PAINT GREEN (-7650 5325);
DISPLAY INVISIBLE (-7650 5325);
FORCEPROP 1 LAST HDL_TAP TRUE
J 2
(-7975 5150);
DISPLAY 0.872340 (-7975 5150);
DISPLAY INVISIBLE (-7975 5150);
FORCEPROP 1 LAST PATH I92
J 2
(-7648 5275);
DISPLAY 0.872340 (-7648 5275);
PAINT GREEN (-7648 5275);
DISPLAY INVISIBLE (-7648 5275);
FORCEADD TAP..1
R 2
(-7650 5325);
FORCEPROP 3 LASTPIN (-7600 5325) SIG_NAME M_J_CPU0_SA_CA<6>
J 0
(-7590 5335);
DISPLAY 0.659574 (-7590 5335);
PAINT MONO (-7590 5335);
DISPLAY INVISIBLE (-7590 5335);
FORCEPROP 1 LASTPIN (-7600 5325) BN 6
J 2
(-7588 5333);
DISPLAY 0.489362 (-7588 5333);
PAINT GREEN (-7588 5333);
FORCEPROP 2 LAST CDS_LIB mstr_standard
J 0
(-7650 5325);
DISPLAY 0.723404 (-7650 5325);
PAINT MONO (-7650 5325);
DISPLAY INVISIBLE (-7650 5325);
FORCEPROP 1 LAST BODY_TYPE PLUMBING
J 2
(-7650 5375);
DISPLAY 0.872340 (-7650 5375);
PAINT GREEN (-7650 5375);
DISPLAY INVISIBLE (-7650 5375);
FORCEPROP 1 LAST HDL_TAP TRUE
J 2
(-7975 5200);
DISPLAY 0.872340 (-7975 5200);
DISPLAY INVISIBLE (-7975 5200);
FORCEPROP 1 LAST PATH I93
J 2
(-7648 5325);
DISPLAY 0.872340 (-7648 5325);
PAINT GREEN (-7648 5325);
DISPLAY INVISIBLE (-7648 5325);
FORCEADD TAP..1
(-5950 3775);
FORCEPROP 3 LASTPIN (-6000 3775) SIG_NAME M_J_CPU0_SA_DQ<0>
J 0
(-5990 3785);
DISPLAY 0.659574 (-5990 3785);
PAINT MONO (-5990 3785);
DISPLAY INVISIBLE (-5990 3785);
FORCEPROP 1 LASTPIN (-6000 3775) BN 0
J 0
(-6012 3783);
DISPLAY 0.489362 (-6012 3783);
PAINT GREEN (-6012 3783);
FORCEPROP 2 LAST CDS_LIB mstr_standard
J 0
(-5950 3775);
DISPLAY 0.723404 (-5950 3775);
PAINT MONO (-5950 3775);
DISPLAY INVISIBLE (-5950 3775);
FORCEPROP 1 LAST BODY_TYPE PLUMBING
J 0
(-5950 3825);
DISPLAY 0.872340 (-5950 3825);
PAINT GREEN (-5950 3825);
DISPLAY INVISIBLE (-5950 3825);
FORCEPROP 1 LAST HDL_TAP TRUE
J 0
(-5625 3650);
DISPLAY 0.872340 (-5625 3650);
DISPLAY INVISIBLE (-5625 3650);
FORCEPROP 1 LAST PATH I94
J 0
(-5952 3775);
DISPLAY 0.872340 (-5952 3775);
PAINT GREEN (-5952 3775);
DISPLAY INVISIBLE (-5952 3775);
FORCEADD TAP..1
(-5950 3875);
FORCEPROP 3 LASTPIN (-6000 3875) SIG_NAME M_J_CPU0_SA_DQ<2>
J 0
(-5990 3885);
DISPLAY 0.659574 (-5990 3885);
PAINT MONO (-5990 3885);
DISPLAY INVISIBLE (-5990 3885);
FORCEPROP 1 LASTPIN (-6000 3875) BN 2
J 0
(-6012 3883);
DISPLAY 0.489362 (-6012 3883);
PAINT GREEN (-6012 3883);
FORCEPROP 2 LAST CDS_LIB mstr_standard
J 0
(-5950 3875);
DISPLAY 0.723404 (-5950 3875);
PAINT MONO (-5950 3875);
DISPLAY INVISIBLE (-5950 3875);
FORCEPROP 1 LAST BODY_TYPE PLUMBING
J 0
(-5950 3925);
DISPLAY 0.872340 (-5950 3925);
PAINT GREEN (-5950 3925);
DISPLAY INVISIBLE (-5950 3925);
FORCEPROP 1 LAST HDL_TAP TRUE
J 0
(-5625 3750);
DISPLAY 0.872340 (-5625 3750);
DISPLAY INVISIBLE (-5625 3750);
FORCEPROP 1 LAST PATH I95
J 0
(-5952 3875);
DISPLAY 0.872340 (-5952 3875);
PAINT GREEN (-5952 3875);
DISPLAY INVISIBLE (-5952 3875);
FORCEADD TAP..1
(-5950 3825);
FORCEPROP 3 LASTPIN (-6000 3825) SIG_NAME M_J_CPU0_SA_DQ<1>
J 0
(-5990 3835);
DISPLAY 0.659574 (-5990 3835);
PAINT MONO (-5990 3835);
DISPLAY INVISIBLE (-5990 3835);
FORCEPROP 1 LASTPIN (-6000 3825) BN 1
J 0
(-6012 3833);
DISPLAY 0.489362 (-6012 3833);
PAINT GREEN (-6012 3833);
FORCEPROP 2 LAST CDS_LIB mstr_standard
J 0
(-5950 3825);
DISPLAY 0.723404 (-5950 3825);
PAINT MONO (-5950 3825);
DISPLAY INVISIBLE (-5950 3825);
FORCEPROP 1 LAST BODY_TYPE PLUMBING
J 0
(-5950 3875);
DISPLAY 0.872340 (-5950 3875);
PAINT GREEN (-5950 3875);
DISPLAY INVISIBLE (-5950 3875);
FORCEPROP 1 LAST HDL_TAP TRUE
J 0
(-5625 3700);
DISPLAY 0.872340 (-5625 3700);
DISPLAY INVISIBLE (-5625 3700);
FORCEPROP 1 LAST PATH I96
J 0
(-5952 3825);
DISPLAY 0.872340 (-5952 3825);
PAINT GREEN (-5952 3825);
DISPLAY INVISIBLE (-5952 3825);
FORCEADD TAP..1
(-5950 3925);
FORCEPROP 3 LASTPIN (-6000 3925) SIG_NAME M_J_CPU0_SA_DQ<3>
J 0
(-5990 3935);
DISPLAY 0.659574 (-5990 3935);
PAINT MONO (-5990 3935);
DISPLAY INVISIBLE (-5990 3935);
FORCEPROP 1 LASTPIN (-6000 3925) BN 3
J 0
(-6012 3933);
DISPLAY 0.489362 (-6012 3933);
PAINT GREEN (-6012 3933);
FORCEPROP 2 LAST CDS_LIB mstr_standard
J 0
(-5950 3925);
DISPLAY 0.723404 (-5950 3925);
PAINT MONO (-5950 3925);
DISPLAY INVISIBLE (-5950 3925);
FORCEPROP 1 LAST BODY_TYPE PLUMBING
J 0
(-5950 3975);
DISPLAY 0.872340 (-5950 3975);
PAINT GREEN (-5950 3975);
DISPLAY INVISIBLE (-5950 3975);
FORCEPROP 1 LAST HDL_TAP TRUE
J 0
(-5625 3800);
DISPLAY 0.872340 (-5625 3800);
DISPLAY INVISIBLE (-5625 3800);
FORCEPROP 1 LAST PATH I97
J 0
(-5952 3925);
DISPLAY 0.872340 (-5952 3925);
PAINT GREEN (-5952 3925);
DISPLAY INVISIBLE (-5952 3925);
FORCEADD TAP..1
(-5950 3975);
FORCEPROP 3 LASTPIN (-6000 3975) SIG_NAME M_J_CPU0_SA_DQ<4>
J 0
(-5990 3985);
DISPLAY 0.659574 (-5990 3985);
PAINT MONO (-5990 3985);
DISPLAY INVISIBLE (-5990 3985);
FORCEPROP 1 LASTPIN (-6000 3975) BN 4
J 0
(-6012 3983);
DISPLAY 0.489362 (-6012 3983);
PAINT GREEN (-6012 3983);
FORCEPROP 2 LAST CDS_LIB mstr_standard
J 0
(-5950 3975);
DISPLAY 0.723404 (-5950 3975);
PAINT MONO (-5950 3975);
DISPLAY INVISIBLE (-5950 3975);
FORCEPROP 1 LAST BODY_TYPE PLUMBING
J 0
(-5950 4025);
DISPLAY 0.872340 (-5950 4025);
PAINT GREEN (-5950 4025);
DISPLAY INVISIBLE (-5950 4025);
FORCEPROP 1 LAST HDL_TAP TRUE
J 0
(-5625 3850);
DISPLAY 0.872340 (-5625 3850);
DISPLAY INVISIBLE (-5625 3850);
FORCEPROP 1 LAST PATH I98
J 0
(-5952 3975);
DISPLAY 0.872340 (-5952 3975);
PAINT GREEN (-5952 3975);
DISPLAY INVISIBLE (-5952 3975);
FORCEADD TAP..1
(-5950 4025);
FORCEPROP 3 LASTPIN (-6000 4025) SIG_NAME M_J_CPU0_SA_DQ<5>
J 0
(-5990 4035);
DISPLAY 0.659574 (-5990 4035);
PAINT MONO (-5990 4035);
DISPLAY INVISIBLE (-5990 4035);
FORCEPROP 1 LASTPIN (-6000 4025) BN 5
J 0
(-6012 4033);
DISPLAY 0.489362 (-6012 4033);
PAINT GREEN (-6012 4033);
FORCEPROP 2 LAST CDS_LIB mstr_standard
J 0
(-5950 4025);
DISPLAY 0.723404 (-5950 4025);
PAINT MONO (-5950 4025);
DISPLAY INVISIBLE (-5950 4025);
FORCEPROP 1 LAST BODY_TYPE PLUMBING
J 0
(-5950 4075);
DISPLAY 0.872340 (-5950 4075);
PAINT GREEN (-5950 4075);
DISPLAY INVISIBLE (-5950 4075);
FORCEPROP 1 LAST HDL_TAP TRUE
J 0
(-5625 3900);
DISPLAY 0.872340 (-5625 3900);
DISPLAY INVISIBLE (-5625 3900);
FORCEPROP 1 LAST PATH I99
J 0
(-5952 4025);
DISPLAY 0.872340 (-5952 4025);
PAINT GREEN (-5952 4025);
DISPLAY INVISIBLE (-5952 4025);
FORCEADD QUANTA_TITLE_BLOCK_C..1
(0 0);
FORCEPROP 0 LAST CDS_CON_LAST_MODIFIED Thu Sep 14 16:12:08 2023
J 0
(-1885 15);
DISPLAY INVISIBLE (-1885 15);
FORCEPROP 1 LAST CUSTOM_TXT_CDS <CON_LAST_MODIFIED>
J 0
(-1885 15);
DISPLAY 0.978723 (-1885 15);
FORCEPROP 2 LAST CUSTOM_TXT_CDS <XR_PAGE_TITLE>
J 0
(-7890 5250);
DISPLAY 0.638298 (-7890 5250);
PAINT PINK (-7890 5250);
DISPLAY INVISIBLE (-7890 5250);
FORCEPROP 1 LAST CUSTOM_TXT_CDS <NAME_2>
J 0
(-3175 50);
FORCEPROP 1 LAST CUSTOM_TXT_CDS <NAME_1>
J 0
(-3175 175);
FORCEPROP 1 LAST CUSTOM_TXT_CDS <Q_NUMBER>
J 0
(-1403 103);
DISPLAY 1.212766 (-1403 103);
FORCEPROP 1 LAST CUSTOM_TXT_CDS <Q_PROJ>
J 0
(-2382 102);
DISPLAY 1.212766 (-2382 102);
FORCEPROP 1 LAST CUSTOM_TXT_CDS <Q_REV>
J 0
(-184 103);
DISPLAY 1.212766 (-184 103);
FORCEPROP 1 LAST CUSTOM_TXT_CDS <CON_PAGE_NUM> OF <CON_TOTAL_PAGES>
J 0
(-446 18);
DISPLAY 0.978723 (-446 18);
FORCEPROP 1 LAST Q_TITLE DDR5 - CPU0 CHJ
J 0
(-9366 26);
DISPLAY 2.446809 (-9366 26);
PAINT GREEN (-9366 26);
FORCEPROP 2 LAST PAGE_BORDER TRUE
J 0
(-7890 5250);
DISPLAY 0.638298 (-7890 5250);
PAINT PINK (-7890 5250);
DISPLAY INVISIBLE (-7890 5250);
FORCEPROP 1 LAST CDS_LMAN_SYM_OUTLINE -9475,6775,100,-125
J 0
(0 0);
DISPLAY 0.468085 (0 0);
PAINT GREEN (0 0);
DISPLAY INVISIBLE (0 0);
FORCEPROP 2 LAST CDS_LIB pure_quanta
J 0
(0 0);
DISPLAY INVISIBLE (0 0);
FORCEPROP 2 LAST CDS_XR_PAGE_TITLE CR-95 : @T6G_MB_LIB.T6G(SCH_1):PAGE95
J 0
(-7890 5250);
DISPLAY 0.638298 (-7890 5250);
PAINT PINK (-7890 5250);
DISPLAY INVISIBLE (-7890 5250);
FORCEPROP 1 LAST Q_DEPT BU9
J 1
(-3763 49);
DISPLAY 1.957447 (-3763 49);
PAINT GREEN (-3763 49);
DISPLAY INVISIBLE (-3763 49);
FORCEPROP 1 LAST COMMENT_BODY TRUE
J 0
(12 -13);
DISPLAY 0.978723 (12 -13);
PAINT GREEN (12 -13);
DISPLAY INVISIBLE (12 -13);
FORCEADD DNS..2
(-8300 2225);
PAINT RED (-8300 2225);
FORCEPROP 2 LAST CDS_LIB mstr_misc
J 0
(-8300 2225);
DISPLAY INVISIBLE (-8300 2225);
FORCEPROP 1 LAST COMMENT_BODY TRUE
R 1
J 0
(-8225 2000);
DISPLAY 0.872340 (-8225 2000);
PAINT PEACH (-8225 2000);
DISPLAY INVISIBLE (-8225 2000);
WIRE 17 -1 (-7700 3400)(-7700 3450);
WIRE 17 -1 (-7700 3400)(-7700 3350);
WIRE 17 -1 (-7700 3500)(-7700 3450);
WIRE 17 -1 (-7700 3500)(-7700 3525);
WIRE 17 -1 (-7700 3300)(-7700 3350);
WIRE 17 -1 (-7700 3250)(-7700 3300);
WIRE 17 -1 (-7700 3525)(-8200 3525);
FORCEPROP 2 LAST SIG_NAME M_J_CPU0_SB_CB<7:0>
J 0
(-8150 3535);
DISPLAY 0.489362 (-8150 3535);
WIRE 17 -1 (-7700 3600)(-7700 3650);
WIRE 17 -1 (-7700 3650)(-7700 3700);
WIRE 17 -1 (-7700 3700)(-7700 3750);
WIRE 17 -1 (-7700 3750)(-7700 3800);
WIRE 17 -1 (-7700 3850)(-7700 3800);
WIRE 17 -1 (-7700 3850)(-7700 3900);
WIRE 17 -1 (-7700 3950)(-7700 3900);
WIRE 17 -1 (-7700 3950)(-7700 3975);
WIRE 17 -1 (-7700 3975)(-8200 3975);
FORCEPROP 2 LAST SIG_NAME M_J_CPU0_SA_CB<7:0>
J 0
(-8150 3985);
DISPLAY 0.489362 (-8150 3985);
WIRE 17 -1 (-7700 5050)(-7700 5100);
WIRE 17 -1 (-7700 5100)(-7700 5150);
WIRE 17 -1 (-7700 5150)(-7700 5200);
WIRE 17 -1 (-7700 5200)(-7700 5250);
WIRE 17 -1 (-7700 5250)(-7700 5300);
WIRE 17 -1 (-7700 5300)(-7700 5350);
WIRE 17 -1 (-7700 5350)(-7700 5375);
WIRE 17 -1 (-7700 5375)(-8200 5375);
FORCEPROP 2 LAST SIG_NAME M_J_CPU0_SA_CA<6:0>
J 0
(-8185 5385);
DISPLAY 0.489362 (-8185 5385);
WIRE 17 -1 (-7700 4650)(-7700 4700);
WIRE 17 -1 (-7700 4700)(-7700 4750);
WIRE 17 -1 (-7700 4750)(-7700 4800);
WIRE 17 -1 (-7700 4800)(-7700 4850);
WIRE 17 -1 (-7700 4850)(-7700 4900);
WIRE 17 -1 (-7700 4900)(-7700 4950);
WIRE 17 -1 (-7700 4950)(-7700 4975);
WIRE 17 -1 (-7700 4975)(-8200 4975);
FORCEPROP 2 LAST SIG_NAME M_J_CPU0_SB_CA<6:0>
J 0
(-8185 4985);
DISPLAY 0.489362 (-8185 4985);
WIRE 17 -1 (-7700 3200)(-7700 3250);
WIRE 17 -1 (-7700 3150)(-7700 3200);
WIRE 17 -1 (-5900 5300)(-5900 5250);
WIRE 17 -1 (-5900 5350)(-5900 5300);
WIRE 17 -1 (-5900 5250)(-5900 5200);
WIRE 17 -1 (-5900 5200)(-5900 5150);
WIRE 17 -1 (-5900 5375)(-5900 5350);
WIRE 17 -1 (-5900 5375)(-5250 5375);
FORCEPROP 2 LAST SIG_NAME M_J_CPU0_SA_DQ<31:0>
J 0
(-5835 5385);
DISPLAY 0.489362 (-5835 5385);
WIRE 17 -1 (-5900 5150)(-5900 5100);
WIRE 17 -1 (-5900 5100)(-5900 5050);
WIRE 17 -1 (-5900 5050)(-5900 5000);
WIRE 17 -1 (-5900 5000)(-5900 4950);
WIRE 17 -1 (-5900 4950)(-5900 4900);
WIRE 17 -1 (-5900 4900)(-5900 4850);
WIRE 17 -1 (-5900 4850)(-5900 4800);
WIRE 17 -1 (-5900 4800)(-5900 4750);
WIRE 17 -1 (-5900 4750)(-5900 4700);
WIRE 17 -1 (-5900 4700)(-5900 4650);
WIRE 17 -1 (-5900 4650)(-5900 4600);
WIRE 17 -1 (-5900 4550)(-5900 4600);
WIRE 17 -1 (-5900 4500)(-5900 4550);
WIRE 17 -1 (-5900 4450)(-5900 4500);
WIRE 17 -1 (-5900 4400)(-5900 4450);
WIRE 17 -1 (-5900 4400)(-5900 4350);
WIRE 17 -1 (-5900 4350)(-5900 4300);
WIRE 17 -1 (-5900 4300)(-5900 4250);
WIRE 17 -1 (-5900 4250)(-5900 4200);
WIRE 17 -1 (-5900 4200)(-5900 4150);
WIRE 17 -1 (-5900 4150)(-5900 4100);
WIRE 17 -1 (-5900 4100)(-5900 4050);
WIRE 17 -1 (-5900 4050)(-5900 4000);
WIRE 17 -1 (-5900 3950)(-5900 4000);
WIRE 17 -1 (-5900 3900)(-5900 3950);
WIRE 17 -1 (-5900 3850)(-5900 3900);
WIRE 17 -1 (-5900 3800)(-5900 3850);
WIRE 17 -1 (-5900 3725)(-5900 3700);
WIRE 17 -1 (-5900 3725)(-5250 3725);
FORCEPROP 2 LAST SIG_NAME M_J_CPU0_SB_DQ<31:0>
J 0
(-5835 3735);
DISPLAY 0.489362 (-5835 3735);
WIRE 17 -1 (-5900 3700)(-5900 3650);
WIRE 17 -1 (-5900 3650)(-5900 3600);
WIRE 17 -1 (-5900 3600)(-5900 3550);
WIRE 17 -1 (-5900 3550)(-5900 3500);
WIRE 17 -1 (-5900 3500)(-5900 3450);
WIRE 17 -1 (-5900 3450)(-5900 3400);
WIRE 17 -1 (-5900 3400)(-5900 3350);
WIRE 17 -1 (-5900 3350)(-5900 3300);
WIRE 17 -1 (-5900 3300)(-5900 3250);
WIRE 17 -1 (-5900 3250)(-5900 3200);
WIRE 17 -1 (-5900 3200)(-5900 3150);
WIRE 17 -1 (-5900 3150)(-5900 3100);
WIRE 17 -1 (-5900 3100)(-5900 3050);
WIRE 17 -1 (-5900 3050)(-5900 3000);
WIRE 17 -1 (-5900 3000)(-5900 2950);
WIRE 17 -1 (-5900 2900)(-5900 2950);
WIRE 17 -1 (-5900 2850)(-5900 2900);
WIRE 17 -1 (-5900 2800)(-5900 2850);
WIRE 17 -1 (-5900 2750)(-5900 2800);
WIRE 17 -1 (-5900 2750)(-5900 2700);
WIRE 17 -1 (-5900 2700)(-5900 2650);
WIRE 17 -1 (-5900 2650)(-5900 2600);
WIRE 17 -1 (-5900 2600)(-5900 2550);
WIRE 17 -1 (-5900 2550)(-5900 2500);
WIRE 17 -1 (-5900 2500)(-5900 2450);
WIRE 17 -1 (-5900 2450)(-5900 2400);
WIRE 17 -1 (-5900 2400)(-5900 2350);
WIRE 17 -1 (-5900 2300)(-5900 2350);
WIRE 17 -1 (-5900 2250)(-5900 2300);
WIRE 17 -1 (-5900 2200)(-5900 2250);
WIRE 17 -1 (-5900 2150)(-5900 2200);
WIRE 17 -1 (-3125 4100)(-3125 4000);
WIRE 17 -1 (-3125 4200)(-3125 4100);
WIRE 17 -1 (-3125 4000)(-3125 3900);
WIRE 17 -1 (-3125 3900)(-3125 3800);
WIRE 17 -1 (-3125 4225)(-3125 4200);
WIRE 17 -1 (-3125 4225)(-2425 4225);
FORCEPROP 2 LAST SIG_NAME M_J_CPU0_SA_DQS_DN<9:0>
J 0
(-3060 4235);
DISPLAY 0.489362 (-3060 4235);
WIRE 17 -1 (-3325 4050)(-3325 3950);
WIRE 17 -1 (-3325 4150)(-3325 4050);
WIRE 17 -1 (-3325 3950)(-3325 3850);
WIRE 17 -1 (-3325 3750)(-3325 3850);
WIRE 17 -1 (-3325 4250)(-3325 4150);
WIRE 17 -1 (-3325 4275)(-3325 4250);
WIRE 17 -1 (-3325 3650)(-3325 3750);
WIRE 17 -1 (-3325 3550)(-3325 3650);
WIRE 17 -1 (-3325 4275)(-2425 4275);
FORCEPROP 2 LAST SIG_NAME M_J_CPU0_SA_DQS_DP<9:0>
J 0
(-3060 4285);
DISPLAY 0.489362 (-3060 4285);
WIRE 17 -1 (-3325 3200)(-3325 3100);
WIRE 17 -1 (-3325 3225)(-3325 3200);
WIRE 17 -1 (-3325 3100)(-3325 3000);
WIRE 17 -1 (-3325 3000)(-3325 2900);
WIRE 17 -1 (-3325 3225)(-2425 3225);
FORCEPROP 2 LAST SIG_NAME M_J_CPU0_SB_DQS_DP<9:0>
J 0
(-3060 3235);
DISPLAY 0.489362 (-3060 3235);
WIRE 17 -1 (-3125 3150)(-3125 3050);
WIRE 17 -1 (-3125 3175)(-3125 3150);
WIRE 17 -1 (-3125 3050)(-3125 2950);
WIRE 17 -1 (-3125 2950)(-3125 2850);
WIRE 17 -1 (-3125 3175)(-2425 3175);
FORCEPROP 2 LAST SIG_NAME M_J_CPU0_SB_DQS_DN<9:0>
J 0
(-3060 3185);
DISPLAY 0.489362 (-3060 3185);
WIRE 17 -1 (-3325 2900)(-3325 2800);
WIRE 17 -1 (-3125 3400)(-3125 3300);
WIRE 17 -1 (-3125 3500)(-3125 3400);
WIRE 17 -1 (-3125 3500)(-3125 3600);
WIRE 17 -1 (-3125 3600)(-3125 3700);
WIRE 17 -1 (-3125 3700)(-3125 3800);
WIRE 17 -1 (-3325 3450)(-3325 3350);
WIRE 17 -1 (-3325 3550)(-3325 3450);
WIRE 17 -1 (-3125 2350)(-3125 2250);
WIRE 17 -1 (-3125 2450)(-3125 2350);
WIRE 17 -1 (-3125 2450)(-3125 2550);
WIRE 17 -1 (-3125 2550)(-3125 2650);
WIRE 17 -1 (-3125 2650)(-3125 2750);
WIRE 17 -1 (-3125 2850)(-3125 2750);
WIRE 17 -1 (-3325 2400)(-3325 2300);
WIRE 17 -1 (-3325 2500)(-3325 2400);
WIRE 17 -1 (-3325 2500)(-3325 2600);
WIRE 17 -1 (-3325 2600)(-3325 2700);
WIRE 17 -1 (-3325 2700)(-3325 2800);
WIRE 16 -1 (-6350 1000)(-6350 1075);
WIRE 16 -1 (-8550 3000)(-8550 3075);
WIRE 16 -1 (-8325 2325)(-8325 2350);
WIRE 16 -1 (-7400 2725)(-7500 2725);
FORCEPROP 2 LAST SIG_NAME I3C_SPD_DDRJ_CPU0_SCL
J 0
(-7885 2735);
DISPLAY 0.446809 (-7885 2735);
FORCEPROP 2 LASTPROP $XRERR UNIQUE?
J 0
(-8125 2735);
DISPLAY 0.638298 (-8125 2735);
PAINT MONO (-8125 2735);
DISPLAY INVISIBLE (-8125 2735);
WIRE 16 -1 (-7500 2725)(-7500 2550);
WIRE 16 -1 (-7500 2550)(-7600 2550);
WIRE 16 -1 (-7400 2975)(-8000 2975);
FORCEPROP 2 LAST SIG_NAME M_J_CPU0_ALERT_N
J 0
(-7985 2985);
DISPLAY 0.489362 (-7985 2985);
WIRE 16 -1 (-7400 3025)(-8000 3025);
FORCEPROP 2 LAST SIG_NAME M_J_CPU0_RESET_N
J 0
(-7985 3035);
DISPLAY 0.489362 (-7985 3035);
WIRE 16 -1 (-7400 4025)(-8200 4025);
FORCEPROP 2 LAST SIG_NAME M_J_CPU0_CLK_DN<0>
J 0
(-8150 4035);
DISPLAY 0.489362 (-8150 4035);
WIRE 16 -1 (-7400 4175)(-8200 4175);
FORCEPROP 2 LAST SIG_NAME M_J_CPU0_SB_CS_N<0>
J 0
(-8150 4185);
DISPLAY 0.489362 (-8150 4185);
WIRE 16 -1 (-7400 4225)(-8200 4225);
FORCEPROP 2 LAST SIG_NAME M_J_CPU0_SB_CS_N<1>
J 0
(-8150 4235);
DISPLAY 0.489362 (-8150 4235);
WIRE 16 -1 (-6000 4275)(-6200 4275);
WIRE 16 -1 (-6200 4325)(-6000 4325);
WIRE 16 -1 (-6000 4375)(-6200 4375);
WIRE 16 -1 (-6000 4425)(-6200 4425);
WIRE 16 -1 (-6000 4475)(-6200 4475);
WIRE 16 -1 (-7400 4775)(-7600 4775);
WIRE 16 -1 (-8950 2075)(-8550 2075);
FORCEPROP 2 LAST SIG_NAME PWRGD_CHGL_CPU0
J 0
(-8935 2085);
DISPLAY 0.489362 (-8935 2085);
WIRE 16 -1 (-6000 3225)(-6200 3225);
WIRE 16 -1 (-6000 3325)(-6200 3325);
WIRE 16 -1 (-6000 3425)(-6200 3425);
WIRE 16 -1 (-6200 3475)(-6000 3475);
WIRE 16 -1 (-6000 5275)(-6200 5275);
WIRE 16 -1 (-7400 1875)(-8200 1875);
FORCEPROP 2 LAST SIG_NAME M_J_CPU0_SB_RSP<0>
J 0
(-8150 1885);
DISPLAY 0.489362 (-8150 1885);
WIRE 16 -1 (-6000 5075)(-6200 5075);
WIRE 16 -1 (-6200 3275)(-6000 3275);
WIRE 16 -1 (-7400 3625)(-7600 3625);
WIRE 16 -1 (-3575 3175)(-3425 3175);
WIRE 16 -1 (-3575 3125)(-3225 3125);
WIRE 16 -1 (-3575 4225)(-3425 4225);
WIRE 16 -1 (-3575 4175)(-3225 4175);
WIRE 16 -1 (-3425 4125)(-3575 4125);
WIRE 16 -1 (-3575 4075)(-3225 4075);
WIRE 16 -1 (-3575 2925)(-3225 2925);
WIRE 16 -1 (-3425 4025)(-3575 4025);
WIRE 16 -1 (-3425 2875)(-3575 2875);
WIRE 16 -1 (-3575 2825)(-3225 2825);
WIRE 16 -1 (-3575 3875)(-3225 3875);
WIRE 16 -1 (-3575 2775)(-3425 2775);
WIRE 16 -1 (-3575 2725)(-3225 2725);
WIRE 16 -1 (-3575 3825)(-3425 3825);
WIRE 16 -1 (-3225 3775)(-3575 3775);
WIRE 16 -1 (-3425 2675)(-3575 2675);
WIRE 16 -1 (-3575 2625)(-3225 2625);
WIRE 16 -1 (-3425 3725)(-3575 3725);
WIRE 16 -1 (-3575 3675)(-3225 3675);
WIRE 16 -1 (-3425 2575)(-3575 2575);
WIRE 16 -1 (-3575 2525)(-3225 2525);
WIRE 16 -1 (-3425 3625)(-3575 3625);
WIRE 16 -1 (-3575 3575)(-3225 3575);
WIRE 16 -1 (-3425 2475)(-3575 2475);
WIRE 16 -1 (-3575 2425)(-3225 2425);
WIRE 16 -1 (-3425 3525)(-3575 3525);
WIRE 16 -1 (-3575 3475)(-3225 3475);
WIRE 16 -1 (-3575 2375)(-3425 2375);
WIRE 16 -1 (-3575 2325)(-3225 2325);
WIRE 16 -1 (-3575 3425)(-3425 3425);
WIRE 16 -1 (-3575 3375)(-3225 3375);
WIRE 16 -1 (-3425 2275)(-3575 2275);
WIRE 16 -1 (-3575 2225)(-3225 2225);
WIRE 16 -1 (-3425 3325)(-3575 3325);
WIRE 16 -1 (-3575 3275)(-3225 3275);
WIRE 16 -1 (-3425 2975)(-3575 2975);
WIRE 16 -1 (-3575 3025)(-3225 3025);
WIRE 16 -1 (-3425 3075)(-3575 3075);
WIRE 16 -1 (-3425 3925)(-3575 3925);
WIRE 16 -1 (-3575 3975)(-3225 3975);
WIRE 16 -1 (-6200 5325)(-6000 5325);
WIRE 16 -1 (-7400 4475)(-8200 4475);
FORCEPROP 2 LAST SIG_NAME M_J_CPU0_SB_PAR
J 0
(-8150 4485);
DISPLAY 0.489362 (-8150 4485);
WIRE 16 -1 (-7400 4525)(-8200 4525);
FORCEPROP 2 LAST SIG_NAME M_J_CPU0_SA_PAR
J 0
(-8150 4535);
DISPLAY 0.489362 (-8150 4535);
WIRE 16 -1 (-6000 2125)(-6200 2125);
WIRE 16 -1 (-6000 2175)(-6200 2175);
WIRE 16 -1 (-6000 2225)(-6200 2225);
WIRE 16 -1 (-6200 2275)(-6000 2275);
WIRE 16 -1 (-6000 2325)(-6200 2325);
WIRE 16 -1 (-6000 2375)(-6200 2375);
WIRE 16 -1 (-6000 2425)(-6200 2425);
WIRE 16 -1 (-6200 2475)(-6000 2475);
WIRE 16 -1 (-6000 2525)(-6200 2525);
WIRE 16 -1 (-6000 2575)(-6200 2575);
WIRE 16 -1 (-6000 2625)(-6200 2625);
WIRE 16 -1 (-6200 2675)(-6000 2675);
WIRE 16 -1 (-6000 2725)(-6200 2725);
WIRE 16 -1 (-6000 2775)(-6200 2775);
WIRE 16 -1 (-6000 2825)(-6200 2825);
WIRE 16 -1 (-6200 2875)(-6000 2875);
WIRE 16 -1 (-6000 2925)(-6200 2925);
WIRE 16 -1 (-6000 2975)(-6200 2975);
WIRE 16 -1 (-6000 3025)(-6200 3025);
WIRE 16 -1 (-6200 3075)(-6000 3075);
WIRE 16 -1 (-6000 3125)(-6200 3125);
WIRE 16 -1 (-6000 3175)(-6200 3175);
WIRE 16 -1 (-6000 3375)(-6200 3375);
WIRE 16 -1 (-6000 3525)(-6200 3525);
WIRE 16 -1 (-6000 3575)(-6200 3575);
WIRE 16 -1 (-6000 3625)(-6200 3625);
WIRE 16 -1 (-6200 3675)(-6000 3675);
WIRE 16 -1 (-6000 3775)(-6200 3775);
WIRE 16 -1 (-6000 3825)(-6200 3825);
WIRE 16 -1 (-6000 3875)(-6200 3875);
WIRE 16 -1 (-6200 3925)(-6000 3925);
WIRE 16 -1 (-6000 3975)(-6200 3975);
WIRE 16 -1 (-6000 4025)(-6200 4025);
WIRE 16 -1 (-6000 4075)(-6200 4075);
WIRE 16 -1 (-6200 4125)(-6000 4125);
WIRE 16 -1 (-6000 4175)(-6200 4175);
WIRE 16 -1 (-6000 4225)(-6200 4225);
WIRE 16 -1 (-6200 4525)(-6000 4525);
WIRE 16 -1 (-6000 4575)(-6200 4575);
WIRE 16 -1 (-6000 4625)(-6200 4625);
WIRE 16 -1 (-6000 4675)(-6200 4675);
WIRE 16 -1 (-6200 4725)(-6000 4725);
WIRE 16 -1 (-6000 4775)(-6200 4775);
WIRE 16 -1 (-6000 4825)(-6200 4825);
WIRE 16 -1 (-6000 4875)(-6200 4875);
WIRE 16 -1 (-6200 4925)(-6000 4925);
WIRE 16 -1 (-6000 4975)(-6200 4975);
WIRE 16 -1 (-6000 5025)(-6200 5025);
WIRE 16 -1 (-6200 5125)(-6000 5125);
WIRE 16 -1 (-6000 5175)(-6200 5175);
WIRE 16 -1 (-6000 5225)(-6200 5225);
WIRE 16 -1 (-7400 4375)(-8200 4375);
FORCEPROP 2 LAST SIG_NAME M_J_CPU0_SA_CS_N<1>
J 0
(-8150 4385);
DISPLAY 0.489362 (-8150 4385);
WIRE 16 -1 (-7400 4325)(-8200 4325);
FORCEPROP 2 LAST SIG_NAME M_J_CPU0_SA_CS_N<0>
J 0
(-8150 4335);
DISPLAY 0.489362 (-8150 4335);
WIRE 16 -1 (-7400 4075)(-8200 4075);
FORCEPROP 2 LAST SIG_NAME M_J_CPU0_CLK_DP<0>
J 0
(-8150 4085);
DISPLAY 0.489362 (-8150 4085);
WIRE 16 -1 (-7400 3125)(-7600 3125);
WIRE 16 -1 (-7400 3175)(-7600 3175);
WIRE 16 -1 (-7400 3225)(-7600 3225);
WIRE 16 -1 (-7400 3275)(-7600 3275);
WIRE 16 -1 (-7400 3325)(-7600 3325);
WIRE 16 -1 (-7400 3675)(-7600 3675);
WIRE 16 -1 (-7400 3725)(-7600 3725);
WIRE 16 -1 (-7400 3825)(-7600 3825);
WIRE 16 -1 (-7400 3875)(-7600 3875);
WIRE 16 -1 (-7400 4925)(-7600 4925);
WIRE 16 -1 (-7400 5325)(-7600 5325);
WIRE 16 -1 (-7400 4875)(-7600 4875);
WIRE 16 -1 (-7400 5275)(-7600 5275);
WIRE 16 -1 (-7400 4825)(-7600 4825);
WIRE 16 -1 (-7400 5225)(-7600 5225);
WIRE 16 -1 (-7400 5175)(-7600 5175);
WIRE 16 -1 (-7400 4725)(-7600 4725);
WIRE 16 -1 (-7400 5125)(-7600 5125);
WIRE 16 -1 (-7400 4675)(-7600 4675);
WIRE 16 -1 (-7400 5075)(-7600 5075);
WIRE 16 -1 (-7400 4625)(-7600 4625);
WIRE 16 -1 (-7400 5025)(-7600 5025);
WIRE 16 -1 (-7400 3475)(-7600 3475);
WIRE 16 -1 (-7400 3775)(-7600 3775);
WIRE 16 -1 (-7400 3925)(-7600 3925);
WIRE 16 -1 (-6350 1350)(-6350 1275);
WIRE 16 -1 (-6350 1350)(-7075 1350);
FORCEPROP 2 LAST SIG_NAME PD_CHJ_CPU0_DIMM_SAA
J 0
(-7060 1360);
DISPLAY 0.489362 (-7060 1360);
WIRE 16 -1 (-7400 3575)(-7600 3575);
WIRE 16 -1 (-7400 3425)(-7600 3425);
WIRE 16 -1 (-7400 3375)(-7600 3375);
WIRE 16 -1 (-7400 1925)(-8200 1925);
FORCEPROP 2 LAST SIG_NAME M_J_CPU0_SA_RSP<0>
J 0
(-8150 1935);
DISPLAY 0.489362 (-8150 1935);
WIRE 16 -1 (-7400 2825)(-8475 2825);
FORCEPROP 2 LAST SIG_NAME PD_CHJ_CPU0_DIMM_SAA
J 0
(-8450 2835);
DISPLAY 0.489362 (-8450 2835);
WIRE 16 -1 (-8325 2125)(-8325 2075);
WIRE 16 -1 (-8125 2075)(-8325 2075);
WIRE 16 -1 (-8325 2075)(-8350 2075);
WIRE 16 -1 (-8125 2075)(-8125 2475);
WIRE 16 -1 (-7400 2475)(-8125 2475);
FORCEPROP 2 LAST SIG_NAME PWRGD_CHJ_CPU0_DIMM
J 0
(-8000 2485);
DISPLAY 0.489362 (-8000 2485);
FORCEPROP 2 LASTPROP $XRERR UNIQUE?
J 0
(-8240 2485);
DISPLAY 0.638298 (-8240 2485);
PAINT MONO (-8240 2485);
DISPLAY INVISIBLE (-8240 2485);
WIRE 16 -1 (-7800 2550)(-8250 2550);
FORCEPROP 2 LAST SIG_NAME I3C_SPD_DDRGL_CPU0_SCL
J 0
(-8310 2560);
DISPLAY 0.489362 (-8310 2560);
WIRE 16 -1 (-8450 2875)(-7400 2875);
WIRE 16 -1 (-8450 3300)(-8450 2875);
WIRE 16 -1 (-8550 3300)(-8450 3300);
WIRE 16 -1 (-8450 3325)(-8450 3300);
WIRE 16 -1 (-8550 3275)(-8550 3300);
WIRE 16 -1 (-2050 5175)(-1750 5175);
WIRE 16 -1 (-2050 5225)(-2050 5175);
WIRE 16 -1 (-1750 5225)(-2050 5225);
WIRE 16 -1 (-2050 5225)(-2050 5275);
WIRE 16 -1 (-1750 5275)(-2050 5275);
WIRE 16 -1 (-2050 5275)(-2050 6025);
WIRE 16 -1 (-2175 6025)(-2050 6025);
WIRE 16 -1 (-2175 6025)(-2175 5925);
WIRE 16 -1 (-2175 6025)(-2750 6025);
WIRE 16 -1 (-2750 5925)(-2750 6025);
WIRE 16 -1 (-2750 6025)(-2750 6100);
WIRE 16 -1 (-2175 5600)(-2175 5725);
WIRE 16 -1 (-2175 5600)(-2750 5600);
WIRE 16 -1 (-2750 5600)(-2750 5725);
WIRE 16 -1 (-2750 5600)(-2750 5525);
WIRE 16 -1 (-250 5275)(-250 5225);
WIRE 16 -1 (-250 5275)(-550 5275);
WIRE 16 -1 (-250 5225)(-250 5175);
WIRE 16 -1 (-250 5225)(-550 5225);
WIRE 16 -1 (-250 5175)(-250 5125);
WIRE 16 -1 (-250 5175)(-550 5175);
WIRE 16 -1 (-250 5125)(-550 5125);
WIRE 16 -1 (-250 5125)(-250 5075);
WIRE 16 -1 (-250 5075)(-250 5025);
WIRE 16 -1 (-250 5075)(-550 5075);
WIRE 16 -1 (-250 5025)(-250 4975);
WIRE 16 -1 (-250 5025)(-550 5025);
WIRE 16 -1 (-250 4975)(-250 4925);
WIRE 16 -1 (-250 4975)(-550 4975);
WIRE 16 -1 (-250 4925)(-250 4875);
WIRE 16 -1 (-250 4925)(-550 4925);
WIRE 16 -1 (-250 4875)(-250 4825);
WIRE 16 -1 (-250 4875)(-550 4875);
WIRE 16 -1 (-250 4825)(-250 4775);
WIRE 16 -1 (-250 4825)(-550 4825);
WIRE 16 -1 (-250 4775)(-250 4725);
WIRE 16 -1 (-250 4775)(-550 4775);
WIRE 16 -1 (-250 4725)(-250 4675);
WIRE 16 -1 (-250 4725)(-550 4725);
WIRE 16 -1 (-250 4675)(-250 4625);
WIRE 16 -1 (-250 4675)(-550 4675);
WIRE 16 -1 (-250 4625)(-250 4575);
WIRE 16 -1 (-250 4625)(-550 4625);
WIRE 16 -1 (-250 4575)(-250 4525);
WIRE 16 -1 (-250 4575)(-550 4575);
WIRE 16 -1 (-250 4525)(-250 4475);
WIRE 16 -1 (-250 4525)(-550 4525);
WIRE 16 -1 (-250 4475)(-250 4425);
WIRE 16 -1 (-250 4475)(-550 4475);
WIRE 16 -1 (-250 4425)(-250 4375);
WIRE 16 -1 (-250 4425)(-550 4425);
WIRE 16 -1 (-250 4375)(-250 4325);
WIRE 16 -1 (-250 4375)(-550 4375);
WIRE 16 -1 (-250 4325)(-250 4275);
WIRE 16 -1 (-250 4325)(-550 4325);
WIRE 16 -1 (-250 4275)(-250 4225);
WIRE 16 -1 (-250 4275)(-550 4275);
WIRE 16 -1 (-250 4225)(-250 4175);
WIRE 16 -1 (-250 4225)(-550 4225);
WIRE 16 -1 (-250 4175)(-250 4125);
WIRE 16 -1 (-250 4175)(-550 4175);
WIRE 16 -1 (-250 4125)(-550 4125);
WIRE 16 -1 (-250 4125)(-250 4075);
WIRE 16 -1 (-250 4075)(-250 4025);
WIRE 16 -1 (-250 4075)(-550 4075);
WIRE 16 -1 (-250 4025)(-250 3975);
WIRE 16 -1 (-250 4025)(-550 4025);
WIRE 16 -1 (-250 3975)(-250 3925);
WIRE 16 -1 (-250 3975)(-550 3975);
WIRE 16 -1 (-250 3925)(-250 3875);
WIRE 16 -1 (-250 3925)(-550 3925);
WIRE 16 -1 (-250 3875)(-250 3825);
WIRE 16 -1 (-250 3875)(-550 3875);
WIRE 16 -1 (-250 3825)(-250 3775);
WIRE 16 -1 (-250 3825)(-550 3825);
WIRE 16 -1 (-250 3775)(-250 3725);
WIRE 16 -1 (-250 3775)(-550 3775);
WIRE 16 -1 (-250 3725)(-250 3675);
WIRE 16 -1 (-250 3725)(-550 3725);
WIRE 16 -1 (-250 3675)(-250 3625);
WIRE 16 -1 (-250 3675)(-550 3675);
WIRE 16 -1 (-250 3625)(-250 3575);
WIRE 16 -1 (-250 3625)(-550 3625);
WIRE 16 -1 (-250 3575)(-250 3525);
WIRE 16 -1 (-250 3575)(-550 3575);
WIRE 16 -1 (-250 3525)(-250 3475);
WIRE 16 -1 (-250 3525)(-550 3525);
WIRE 16 -1 (-250 3475)(-250 3425);
WIRE 16 -1 (-250 3475)(-550 3475);
WIRE 16 -1 (-250 3425)(-250 3375);
WIRE 16 -1 (-250 3425)(-550 3425);
WIRE 16 -1 (-250 3375)(-250 3325);
WIRE 16 -1 (-250 3375)(-550 3375);
WIRE 16 -1 (-250 3325)(-250 3275);
WIRE 16 -1 (-250 3325)(-550 3325);
WIRE 16 -1 (-250 3275)(-250 3225);
WIRE 16 -1 (-250 3275)(-550 3275);
WIRE 16 -1 (-250 3225)(-250 3175);
WIRE 16 -1 (-250 3225)(-550 3225);
WIRE 16 -1 (-250 3175)(-250 3125);
WIRE 16 -1 (-250 3175)(-550 3175);
WIRE 16 -1 (-250 3125)(-250 3075);
WIRE 16 -1 (-250 3125)(-550 3125);
WIRE 16 -1 (-250 3075)(-550 3075);
WIRE 16 -1 (-250 3075)(-250 3025);
WIRE 16 -1 (-250 3025)(-250 2975);
WIRE 16 -1 (-250 3025)(-550 3025);
WIRE 16 -1 (-250 2975)(-250 2925);
WIRE 16 -1 (-250 2975)(-550 2975);
WIRE 16 -1 (-250 2925)(-250 2875);
WIRE 16 -1 (-250 2925)(-550 2925);
WIRE 16 -1 (-250 2875)(-250 2825);
WIRE 16 -1 (-250 2875)(-550 2875);
WIRE 16 -1 (-250 2825)(-250 2775);
WIRE 16 -1 (-250 2825)(-550 2825);
WIRE 16 -1 (-250 2775)(-250 2725);
WIRE 16 -1 (-250 2775)(-550 2775);
WIRE 16 -1 (-250 2725)(-250 2675);
WIRE 16 -1 (-250 2725)(-550 2725);
WIRE 16 -1 (-250 2675)(-250 2625);
WIRE 16 -1 (-250 2675)(-550 2675);
WIRE 16 -1 (-250 2625)(-250 2575);
WIRE 16 -1 (-250 2625)(-550 2625);
WIRE 16 -1 (-250 2575)(-250 2525);
WIRE 16 -1 (-250 2575)(-550 2575);
WIRE 16 -1 (-250 2525)(-250 2475);
WIRE 16 -1 (-250 2525)(-550 2525);
WIRE 16 -1 (-250 2475)(-250 2425);
WIRE 16 -1 (-250 2475)(-550 2475);
WIRE 16 -1 (-250 2425)(-250 2375);
WIRE 16 -1 (-250 2425)(-550 2425);
WIRE 16 -1 (-250 2375)(-250 2325);
WIRE 16 -1 (-250 2375)(-550 2375);
WIRE 16 -1 (-250 2325)(-250 2275);
WIRE 16 -1 (-250 2325)(-550 2325);
WIRE 16 -1 (-250 2275)(-250 2225);
WIRE 16 -1 (-250 2275)(-550 2275);
WIRE 16 -1 (-250 2225)(-250 2175);
WIRE 16 -1 (-250 2225)(-550 2225);
WIRE 16 -1 (-250 2175)(-250 2125);
WIRE 16 -1 (-250 2175)(-550 2175);
WIRE 16 -1 (-250 2125)(-550 2125);
WIRE 16 -1 (-250 2125)(-250 2025);
WIRE 16 -1 (-250 2025)(-250 1975);
WIRE 16 -1 (-250 2025)(-550 2025);
WIRE 16 -1 (-250 1975)(-250 1925);
WIRE 16 -1 (-250 1975)(-550 1975);
WIRE 16 -1 (-250 1925)(-250 1675);
WIRE 16 -1 (-250 1925)(-550 1925);
WIRE 16 -1 (-1750 5125)(-2050 5125);
WIRE 16 -1 (-2050 5125)(-2050 5075);
WIRE 16 -1 (-1750 5075)(-2050 5075);
WIRE 16 -1 (-2050 5075)(-2050 5025);
WIRE 16 -1 (-1750 5025)(-2050 5025);
WIRE 16 -1 (-2050 5025)(-2050 4975);
WIRE 16 -1 (-1750 4975)(-2050 4975);
WIRE 16 -1 (-2050 4975)(-2050 4925);
WIRE 16 -1 (-1750 4925)(-2050 4925);
WIRE 16 -1 (-2050 4925)(-2050 4875);
WIRE 16 -1 (-1750 4875)(-2050 4875);
WIRE 16 -1 (-2050 4875)(-2050 4825);
WIRE 16 -1 (-1750 4825)(-2050 4825);
WIRE 16 -1 (-2050 4825)(-2050 4775);
WIRE 16 -1 (-1750 4775)(-2050 4775);
WIRE 16 -1 (-2050 4775)(-2050 4725);
WIRE 16 -1 (-1750 4725)(-2050 4725);
WIRE 16 -1 (-2050 4725)(-2050 4675);
WIRE 16 -1 (-1750 4675)(-2050 4675);
WIRE 16 -1 (-2050 4675)(-2050 4625);
WIRE 16 -1 (-1750 4625)(-2050 4625);
WIRE 16 -1 (-2050 4625)(-2050 4575);
WIRE 16 -1 (-1750 4575)(-2050 4575);
WIRE 16 -1 (-2050 4575)(-2050 4525);
WIRE 16 -1 (-1750 4525)(-2050 4525);
WIRE 16 -1 (-2050 4525)(-2050 4475);
WIRE 16 -1 (-1750 4475)(-2050 4475);
WIRE 16 -1 (-2050 4475)(-2050 4425);
WIRE 16 -1 (-1750 4425)(-2050 4425);
WIRE 16 -1 (-2050 4425)(-2050 4375);
WIRE 16 -1 (-1750 4375)(-2050 4375);
WIRE 16 -1 (-2050 4375)(-2050 4325);
WIRE 16 -1 (-1750 4325)(-2050 4325);
WIRE 16 -1 (-2050 4325)(-2050 4275);
WIRE 16 -1 (-1750 4275)(-2050 4275);
WIRE 16 -1 (-2050 4275)(-2050 4225);
WIRE 16 -1 (-1750 4225)(-2050 4225);
WIRE 16 -1 (-2050 4225)(-2050 4175);
WIRE 16 -1 (-1750 4175)(-2050 4175);
WIRE 16 -1 (-2050 4175)(-2050 4125);
WIRE 16 -1 (-1750 4125)(-2050 4125);
WIRE 16 -1 (-2050 4125)(-2050 4075);
WIRE 16 -1 (-1750 4075)(-2050 4075);
WIRE 16 -1 (-2050 4075)(-2050 4025);
WIRE 16 -1 (-1750 4025)(-2050 4025);
WIRE 16 -1 (-2050 4025)(-2050 3975);
WIRE 16 -1 (-1750 3975)(-2050 3975);
WIRE 16 -1 (-2050 3975)(-2050 3925);
WIRE 16 -1 (-1750 3925)(-2050 3925);
WIRE 16 -1 (-2050 3925)(-2050 3875);
WIRE 16 -1 (-1750 3875)(-2050 3875);
WIRE 16 -1 (-2050 3875)(-2050 3825);
WIRE 16 -1 (-1750 3825)(-2050 3825);
WIRE 16 -1 (-2050 3825)(-2050 3775);
WIRE 16 -1 (-1750 3775)(-2050 3775);
WIRE 16 -1 (-2050 3775)(-2050 3725);
WIRE 16 -1 (-1750 3725)(-2050 3725);
WIRE 16 -1 (-2050 3725)(-2050 3675);
WIRE 16 -1 (-1750 3675)(-2050 3675);
WIRE 16 -1 (-2050 3675)(-2050 3625);
WIRE 16 -1 (-1750 3625)(-2050 3625);
WIRE 16 -1 (-2050 3625)(-2050 3575);
WIRE 16 -1 (-1750 3575)(-2050 3575);
WIRE 16 -1 (-2050 3575)(-2050 3525);
WIRE 16 -1 (-1750 3525)(-2050 3525);
WIRE 16 -1 (-2050 3525)(-2050 3475);
WIRE 16 -1 (-1750 3475)(-2050 3475);
WIRE 16 -1 (-2050 3475)(-2050 3425);
WIRE 16 -1 (-1750 3425)(-2050 3425);
WIRE 16 -1 (-2050 3425)(-2050 3375);
WIRE 16 -1 (-1750 3375)(-2050 3375);
WIRE 16 -1 (-2050 3375)(-2050 3325);
WIRE 16 -1 (-1750 3325)(-2050 3325);
WIRE 16 -1 (-2050 3325)(-2050 3275);
WIRE 16 -1 (-1750 3275)(-2050 3275);
WIRE 16 -1 (-2050 3275)(-2050 3225);
WIRE 16 -1 (-1750 3225)(-2050 3225);
WIRE 16 -1 (-2050 3225)(-2050 3175);
WIRE 16 -1 (-1750 3175)(-2050 3175);
WIRE 16 -1 (-2050 3175)(-2050 3125);
WIRE 16 -1 (-1750 3125)(-2050 3125);
WIRE 16 -1 (-2050 3125)(-2050 3075);
WIRE 16 -1 (-1750 3075)(-2050 3075);
WIRE 16 -1 (-2050 3075)(-2050 3025);
WIRE 16 -1 (-1750 3025)(-2050 3025);
WIRE 16 -1 (-2050 3025)(-2050 2975);
WIRE 16 -1 (-1750 2975)(-2050 2975);
WIRE 16 -1 (-2050 2975)(-2050 2925);
WIRE 16 -1 (-1750 2925)(-2050 2925);
WIRE 16 -1 (-2050 2925)(-2050 2875);
WIRE 16 -1 (-1750 2875)(-2050 2875);
WIRE 16 -1 (-2050 2875)(-2050 2825);
WIRE 16 -1 (-1750 2825)(-2050 2825);
WIRE 16 -1 (-2050 2825)(-2050 2775);
WIRE 16 -1 (-1750 2775)(-2050 2775);
WIRE 16 -1 (-2050 2775)(-2050 2725);
WIRE 16 -1 (-1750 2725)(-2050 2725);
WIRE 16 -1 (-2050 2725)(-2050 2675);
WIRE 16 -1 (-1750 2675)(-2050 2675);
WIRE 16 -1 (-2050 2675)(-2050 2625);
WIRE 16 -1 (-1750 2625)(-2050 2625);
WIRE 16 -1 (-2050 2625)(-2050 2575);
WIRE 16 -1 (-1750 2575)(-2050 2575);
WIRE 16 -1 (-2050 2575)(-2050 2525);
WIRE 16 -1 (-1750 2525)(-2050 2525);
WIRE 16 -1 (-2050 2525)(-2050 2475);
WIRE 16 -1 (-1750 2475)(-2050 2475);
WIRE 16 -1 (-2050 2475)(-2050 2425);
WIRE 16 -1 (-1750 2425)(-2050 2425);
WIRE 16 -1 (-2050 2425)(-2050 2375);
WIRE 16 -1 (-1750 2375)(-2050 2375);
WIRE 16 -1 (-2050 2375)(-2050 2325);
WIRE 16 -1 (-1750 2325)(-2050 2325);
WIRE 16 -1 (-2050 2325)(-2050 2275);
WIRE 16 -1 (-1750 2275)(-2050 2275);
WIRE 16 -1 (-2050 2275)(-2050 2225);
WIRE 16 -1 (-1750 2225)(-2050 2225);
WIRE 16 -1 (-2050 2225)(-2050 2175);
WIRE 16 -1 (-1750 2175)(-2050 2175);
WIRE 16 -1 (-2050 2175)(-2050 2125);
WIRE 16 -1 (-1750 2125)(-2050 2125);
WIRE 16 -1 (-2050 2125)(-2050 2075);
WIRE 16 -1 (-1750 2075)(-2050 2075);
WIRE 16 -1 (-2050 2075)(-2050 2025);
WIRE 16 -1 (-1750 2025)(-2050 2025);
WIRE 16 -1 (-2050 2025)(-2050 1900);
WIRE 16 -1 (-7400 2775)(-8000 2775);
FORCEPROP 2 LAST SIG_NAME I3C_SPD_DDRJ_CPU0_SDA
J 0
(-7910 2785);
DISPLAY 0.446809 (-7910 2785);
FORCEPROP 2 LASTPROP $XRERR UNIQUE?
J 0
(-8150 2785);
DISPLAY 0.638298 (-8150 2785);
PAINT MONO (-8150 2785);
DISPLAY INVISIBLE (-8150 2785);
WIRE 16 -1 (-8225 2650)(-8225 2775);
WIRE 16 -1 (-8225 2650)(-8750 2650);
FORCEPROP 2 LAST SIG_NAME I3C_SPD_DDRGL_CPU0_SDA
J 0
(-8760 2660);
DISPLAY 0.489362 (-8760 2660);
WIRE 16 -1 (-8225 2775)(-8200 2775);
DOT 1 (-8325 2075);
DOT 1 (-2050 5275);
DOT 1 (-2050 4325);
DOT 1 (-2050 4175);
DOT 1 (-250 5225);
DOT 1 (-250 5175);
DOT 1 (-250 5075);
DOT 1 (-250 5125);
DOT 1 (-250 4975);
DOT 1 (-250 5025);
DOT 1 (-250 4925);
DOT 1 (-250 4825);
DOT 1 (-250 4875);
DOT 1 (-250 4725);
DOT 1 (-250 4775);
DOT 1 (-250 4675);
DOT 1 (-250 4575);
DOT 1 (-250 4625);
DOT 1 (-250 4425);
DOT 1 (-250 4525);
DOT 1 (-250 4475);
DOT 1 (-250 4325);
DOT 1 (-250 4375);
DOT 1 (-250 4175);
DOT 1 (-250 4275);
DOT 1 (-250 4225);
DOT 1 (-250 4075);
DOT 1 (-250 4125);
DOT 1 (-250 4025);
DOT 1 (-250 3925);
DOT 1 (-250 3975);
DOT 1 (-2050 5225);
DOT 1 (-2050 5075);
DOT 1 (-2050 4975);
DOT 1 (-2050 5025);
DOT 1 (-2050 4925);
DOT 1 (-2050 4825);
DOT 1 (-2050 4875);
DOT 1 (-2050 4775);
DOT 1 (-2050 4725);
DOT 1 (-2050 4675);
DOT 1 (-2050 4575);
DOT 1 (-2050 4625);
DOT 1 (-2050 4425);
DOT 1 (-2050 4475);
DOT 1 (-2050 4525);
DOT 1 (-2050 4375);
DOT 1 (-2050 4225);
DOT 1 (-2050 4275);
DOT 1 (-2050 4075);
DOT 1 (-2050 4125);
DOT 1 (-2050 4025);
DOT 1 (-2050 3975);
DOT 1 (-2050 3925);
DOT 1 (-250 3825);
DOT 1 (-250 3875);
DOT 1 (-250 3775);
DOT 1 (-250 3675);
DOT 1 (-250 3725);
DOT 1 (-250 3575);
DOT 1 (-250 3625);
DOT 1 (-250 3525);
DOT 1 (-250 3425);
DOT 1 (-250 3475);
DOT 1 (-250 3275);
DOT 1 (-250 3375);
DOT 1 (-250 3325);
DOT 1 (-250 3175);
DOT 1 (-250 3225);
DOT 1 (-250 3025);
DOT 1 (-250 3125);
DOT 1 (-250 3075);
DOT 1 (-250 2925);
DOT 1 (-250 2975);
DOT 1 (-250 2875);
DOT 1 (-250 2775);
DOT 1 (-250 2825);
DOT 1 (-250 2675);
DOT 1 (-250 2725);
DOT 1 (-250 2625);
DOT 1 (-250 2525);
DOT 1 (-250 2575);
DOT 1 (-250 2375);
DOT 1 (-250 2475);
DOT 1 (-250 2425);
DOT 1 (-250 2275);
DOT 1 (-250 2325);
DOT 1 (-250 2125);
DOT 1 (-250 2175);
DOT 1 (-250 2225);
DOT 1 (-250 2025);
DOT 1 (-250 1925);
DOT 1 (-250 1975);
DOT 1 (-2050 3875);
DOT 1 (-2050 3825);
DOT 1 (-2050 3775);
DOT 1 (-2050 3675);
DOT 1 (-2050 3725);
DOT 1 (-2050 3575);
DOT 1 (-2050 3625);
DOT 1 (-2050 3525);
DOT 1 (-2050 3425);
DOT 1 (-2050 3475);
DOT 1 (-2050 3275);
DOT 1 (-2050 3325);
DOT 1 (-2050 3375);
DOT 1 (-2050 3175);
DOT 1 (-2050 3225);
DOT 1 (-2050 3025);
DOT 1 (-2050 3075);
DOT 1 (-2050 3125);
DOT 1 (-2050 2925);
DOT 1 (-2050 2975);
DOT 1 (-2050 2875);
DOT 1 (-2050 2775);
DOT 1 (-2050 2825);
DOT 1 (-2050 2725);
DOT 1 (-2050 2675);
DOT 1 (-2050 2625);
DOT 1 (-2050 2525);
DOT 1 (-2050 2575);
DOT 1 (-2050 2375);
DOT 1 (-2050 2425);
DOT 1 (-2050 2475);
DOT 1 (-2050 2275);
DOT 1 (-2050 2325);
DOT 1 (-2050 2125);
DOT 1 (-2050 2175);
DOT 1 (-2050 2225);
DOT 1 (-2050 2025);
DOT 1 (-2050 2075);
DOT 1 (-8450 3300);
DOT 1 (-2750 5600);
DOT 1 (-2750 6025);
DOT 1 (-2175 6025);
QUIT
